FILE_TYPE = MACRO_DRAWING;
SET COLOR_WIRE YELLOW;
SET COLOR_PROP ORANGE;
SET COLOR_DOT WHITE;
SET COLOR_ARC YELLOW;
SET COLOR_BODY GREEN;
SET COLOR_NOTE PURPLE;
SET PROP_DISPLAY VALUE;
SET PAGE_NUMBER P257;
FORCEADD OFFPAGE..1
(-5075 1575);
PAINT AQUA (-5075 1575);
FORCEPROP 2 LAST $XR3 248 
J 0
(-5357 1539);
DISPLAY 0.638298 (-5357 1539);
PAINT MONO (-5357 1539);
FORCEPROP 2 LAST $XR2 142 
J 0
(-5597 1575);
DISPLAY 0.638298 (-5597 1575);
PAINT MONO (-5597 1575);
FORCEPROP 2 LAST $XR1 141 
J 0
(-5477 1575);
DISPLAY 0.638298 (-5477 1575);
PAINT MONO (-5477 1575);
FORCEPROP 2 LAST $XR0 140 
J 0
(-5357 1575);
DISPLAY 0.638298 (-5357 1575);
PAINT MONO (-5357 1575);
FORCEPROP 2 LAST CDS_LIB standard
J 0
(-5075 1575);
DISPLAY INVISIBLE (-5075 1575);
FORCEPROP 1 LAST OFFPAGE TRUE
J 0
(-4750 1450);
DISPLAY 0.872340 (-4750 1450);
PAINT AQUA (-4750 1450);
DISPLAY INVISIBLE (-4750 1450);
FORCEPROP 1 LAST COMMENT_BODY TRUE
J 0
(-4950 1475);
DISPLAY 0.872340 (-4950 1475);
PAINT GREEN (-4950 1475);
DISPLAY INVISIBLE (-4950 1475);
FORCEPROP 2 LAST PATH I1
J 0
(-5025 1650);
DISPLAY 0.680851 (-5025 1650);
DISPLAY INVISIBLE (-5025 1650);
FORCEADD Q_RES..2
R 2
(-1825 -225);
FORCEPROP 1 LAST LOCATION R1176
J 2
(-1870 -100);
DISPLAY 0.808511 (-1870 -100);
FORCEPROP 0 LAST $SEC 1
J 0
(-1850 -50);
DISPLAY 0.680851 (-1850 -50);
PAINT MONO (-1850 -50);
DISPLAY INVISIBLE (-1850 -50);
FORCEPROP 0 LAST CDS_SEC 1
J 0
(-1850 -50);
DISPLAY 0.680851 (-1850 -50);
DISPLAY INVISIBLE (-1850 -50);
FORCEPROP 1 LASTPIN (-1825 -125) $PN 1
J 2
(-1830 -163);
DISPLAY 0.787234 (-1830 -163);
PAINT MONO (-1830 -163);
FORCEPROP 1 LASTPIN (-1825 -325) $PN 2
J 2
(-1830 -315);
DISPLAY 0.787234 (-1830 -315);
PAINT MONO (-1830 -315);
FORCEPROP 1 LAST VALUE 10K
J 2
(-1870 -150);
DISPLAY 0.638298 (-1870 -150);
FORCEPROP 1 LAST WATTAGE 1/16W
J 2
(-1865 -250);
DISPLAY 0.638298 (-1865 -250);
FORCEPROP 1 LAST PACK_TYPE 0402LF
J 2
(-1865 -400);
DISPLAY 0.638298 (-1865 -400);
FORCEPROP 1 LAST TOLERANCE 1%
J 2
(-1870 -200);
DISPLAY 0.638298 (-1870 -200);
FORCEPROP 1 LAST MATERIAL CHIP
J 2
(-1865 -300);
DISPLAY 0.638298 (-1865 -300);
FORCEPROP 2 LAST CDS_LIB pure_quanta
J 0
(-1825 -225);
DISPLAY INVISIBLE (-1825 -225);
FORCEPROP 1 LAST PATH I10
J 2
(-1875 -50);
DISPLAY 0.978723 (-1875 -50);
PAINT WHITE (-1875 -50);
DISPLAY INVISIBLE (-1875 -50);
FORCEPROP 1 LAST PART_NUMBER CS31002FB08
J 2
(-1865 -350);
DISPLAY 0.638298 (-1865 -350);
DISPLAY INVISIBLE (-1865 -350);
FORCEADD UNIVERSAL_POWER..1
R 2
(-1825 100);
FORCEPROP 3 LASTPIN (-1825 50) SIG_NAME P3V3_AUX\g
J 0
(-1815 60);
DISPLAY 0.659574 (-1815 60);
PAINT MONO (-1815 60);
DISPLAY INVISIBLE (-1815 60);
FORCEPROP 1 LAST HDL_POWER P3V3_AUX
J 1
(-1825 150);
DISPLAY 0.723404 (-1825 150);
PAINT GREEN (-1825 150);
FORCEPROP 2 LAST CDS_LIB pure_quanta_power
J 0
(-1825 100);
DISPLAY INVISIBLE (-1825 100);
FORCEPROP 1 LAST PATH I11
J 2
(-1875 125);
DISPLAY 0.872340 (-1875 125);
PAINT AQUA (-1875 125);
DISPLAY INVISIBLE (-1875 125);
FORCEADD Q_RES..1
(-1275 -450);
FORCEPROP 1 LAST LOCATION R1178
J 0
(-1475 -450);
DISPLAY 0.723404 (-1475 -450);
FORCEPROP 0 LAST $SEC 1
J 0
(-1025 -400);
DISPLAY 0.680851 (-1025 -400);
PAINT MONO (-1025 -400);
DISPLAY INVISIBLE (-1025 -400);
FORCEPROP 0 LAST CDS_SEC 1
J 0
(-1025 -400);
DISPLAY 0.680851 (-1025 -400);
DISPLAY INVISIBLE (-1025 -400);
FORCEPROP 1 LASTPIN (-1375 -450) $PN 1
J 0
(-1363 -438);
DISPLAY 0.787234 (-1363 -438);
PAINT MONO (-1363 -438);
FORCEPROP 1 LASTPIN (-1175 -450) $PN 2
J 0
(-1213 -438);
DISPLAY 0.787234 (-1213 -438);
PAINT MONO (-1213 -438);
FORCEPROP 1 LAST VALUE 33.2
J 2
(-1025 -450);
DISPLAY 0.723404 (-1025 -450);
FORCEPROP 1 LAST MATERIAL CHIP
J 0
(-1250 -500);
DISPLAY 0.723404 (-1250 -500);
FORCEPROP 1 LAST PACK_TYPE 0402LF
J 0
(-1450 -500);
DISPLAY 0.723404 (-1450 -500);
FORCEPROP 1 LAST WATTAGE 1/16W
J 2
(-875 -500);
DISPLAY 0.723404 (-875 -500);
PAINT SKYBLUE (-875 -500);
DISPLAY INVISIBLE (-875 -500);
FORCEPROP 1 LAST TOLERANCE 1%
J 0
(-800 -450);
DISPLAY 0.723404 (-800 -450);
PAINT SKYBLUE (-800 -450);
DISPLAY INVISIBLE (-800 -450);
FORCEPROP 2 LAST CDS_LIB pure_quanta
J 0
(-1275 -450);
DISPLAY INVISIBLE (-1275 -450);
FORCEPROP 1 LAST PATH I12
J 0
(-1325 -300);
DISPLAY 0.978723 (-1325 -300);
PAINT WHITE (-1325 -300);
DISPLAY INVISIBLE (-1325 -300);
FORCEPROP 1 LAST PART_NUMBER CS03322FB03
J 0
(-1675 -550);
DISPLAY 0.723404 (-1675 -550);
PAINT WHITE (-1675 -550);
DISPLAY INVISIBLE (-1675 -550);
FORCEADD UNIVERSAL_GND..1
(-250 -375);
FORCEPROP 3 LASTPIN (-250 -325) SIG_NAME GND\g
J 0
(-240 -315);
DISPLAY 0.659574 (-240 -315);
PAINT MONO (-240 -315);
DISPLAY INVISIBLE (-240 -315);
FORCEPROP 2 LAST CDS_LIB pure_quanta_power
J 0
(-250 -375);
DISPLAY INVISIBLE (-250 -375);
FORCEPROP 1 LAST HDL_POWER GND
J 1
(-225 -450);
DISPLAY 0.872340 (-225 -450);
PAINT GREEN (-225 -450);
DISPLAY INVISIBLE (-225 -450);
FORCEPROP 1 LAST PATH I13
J 0
(-175 -375);
DISPLAY 0.872340 (-175 -375);
PAINT AQUA (-175 -375);
DISPLAY INVISIBLE (-175 -375);
FORCEADD Q_CAP..1
R 2
(-250 -175);
FORCEPROP 1 LAST LOCATION C1065
J 2
(-300 -75);
DISPLAY 0.638298 (-300 -75);
FORCEPROP 0 LAST $SEC 1
J 2
(-300 -25);
DISPLAY 0.680851 (-300 -25);
PAINT MONO (-300 -25);
DISPLAY INVISIBLE (-300 -25);
FORCEPROP 0 LAST CDS_SEC 1
J 2
(-300 -25);
DISPLAY 0.680851 (-300 -25);
DISPLAY INVISIBLE (-300 -25);
FORCEPROP 1 LASTPIN (-250 -75) $PN 1
J 2
(-260 -95);
DISPLAY 0.787234 (-260 -95);
PAINT MONO (-260 -95);
FORCEPROP 1 LASTPIN (-250 -275) $PN 2
J 2
(-260 -295);
DISPLAY 0.787234 (-260 -295);
PAINT MONO (-260 -295);
FORCEPROP 1 LAST MATERIAL X7R
J 2
(-300 -275);
DISPLAY 0.510638 (-300 -275);
PAINT RED (-300 -275);
FORCEPROP 1 LAST VALUE 0.1UF
J 2
(-300 -125);
DISPLAY 0.510638 (-300 -125);
FORCEPROP 1 LAST PACK_TYPE 0402
J 2
(-300 -375);
DISPLAY 0.510638 (-300 -375);
FORCEPROP 1 LAST VOLTAGE 25V
J 2
(-300 -175);
DISPLAY 0.510638 (-300 -175);
FORCEPROP 1 LAST TOLERANCE 10%
J 2
(-300 -225);
DISPLAY 0.510638 (-300 -225);
FORCEPROP 2 LAST CDS_LIB pure_quanta
J 2
(-250 -175);
DISPLAY INVISIBLE (-250 -175);
FORCEPROP 1 LAST PATH I14
J 2
(-300 -25);
DISPLAY 0.978723 (-300 -25);
PAINT WHITE (-300 -25);
DISPLAY INVISIBLE (-300 -25);
FORCEPROP 1 LAST PART_NUMBER CH4104K1B00
J 2
(-300 -325);
DISPLAY 0.510638 (-300 -325);
DISPLAY INVISIBLE (-300 -325);
FORCEADD UNIVERSAL_POWER..1
R 2
(-225 50);
FORCEPROP 3 LASTPIN (-225 0) SIG_NAME P3V3_AUX\g
J 0
(-215 10);
DISPLAY 0.659574 (-215 10);
PAINT MONO (-215 10);
DISPLAY INVISIBLE (-215 10);
FORCEPROP 1 LAST HDL_POWER P3V3_AUX
J 1
(-225 100);
DISPLAY 0.723404 (-225 100);
PAINT GREEN (-225 100);
FORCEPROP 2 LAST CDS_LIB pure_quanta_power
J 0
(-225 50);
DISPLAY INVISIBLE (-225 50);
FORCEPROP 1 LAST PATH I15
J 2
(-275 75);
DISPLAY 0.872340 (-275 75);
PAINT AQUA (-275 75);
DISPLAY INVISIBLE (-275 75);
FORCEADD Q_RES..1
(-1200 725);
FORCEPROP 1 LAST LOCATION R1173
J 0
(-1400 725);
DISPLAY 0.723404 (-1400 725);
FORCEPROP 0 LAST $SEC 1
J 0
(-950 775);
DISPLAY 0.680851 (-950 775);
PAINT MONO (-950 775);
DISPLAY INVISIBLE (-950 775);
FORCEPROP 0 LAST CDS_SEC 1
J 0
(-950 775);
DISPLAY 0.680851 (-950 775);
DISPLAY INVISIBLE (-950 775);
FORCEPROP 1 LASTPIN (-1300 725) $PN 1
J 0
(-1288 737);
DISPLAY 0.787234 (-1288 737);
PAINT MONO (-1288 737);
FORCEPROP 1 LASTPIN (-1100 725) $PN 2
J 0
(-1138 737);
DISPLAY 0.787234 (-1138 737);
PAINT MONO (-1138 737);
FORCEPROP 1 LAST MATERIAL CHIP
J 0
(-1175 675);
DISPLAY 0.723404 (-1175 675);
FORCEPROP 1 LAST PACK_TYPE 0402LF
J 0
(-1375 675);
DISPLAY 0.723404 (-1375 675);
FORCEPROP 1 LAST VALUE 33.2
J 2
(-950 725);
DISPLAY 0.723404 (-950 725);
FORCEPROP 1 LAST WATTAGE 1/16W
J 2
(-800 675);
DISPLAY 0.723404 (-800 675);
PAINT SKYBLUE (-800 675);
DISPLAY INVISIBLE (-800 675);
FORCEPROP 1 LAST TOLERANCE 1%
J 0
(-725 725);
DISPLAY 0.723404 (-725 725);
PAINT SKYBLUE (-725 725);
DISPLAY INVISIBLE (-725 725);
FORCEPROP 2 LAST CDS_LIB pure_quanta
J 0
(-1200 725);
DISPLAY INVISIBLE (-1200 725);
FORCEPROP 1 LAST PATH I16
J 0
(-1250 875);
DISPLAY 0.978723 (-1250 875);
PAINT WHITE (-1250 875);
DISPLAY INVISIBLE (-1250 875);
FORCEPROP 1 LAST PART_NUMBER CS03322FB03
J 0
(-1600 625);
DISPLAY 0.723404 (-1600 625);
PAINT WHITE (-1600 625);
DISPLAY INVISIBLE (-1600 625);
FORCEADD Q_RES..1
(-1200 825);
FORCEPROP 1 LAST LOCATION R1174
J 0
(-1400 825);
DISPLAY 0.723404 (-1400 825);
FORCEPROP 0 LAST $SEC 1
J 0
(-950 875);
DISPLAY 0.680851 (-950 875);
PAINT MONO (-950 875);
DISPLAY INVISIBLE (-950 875);
FORCEPROP 0 LAST CDS_SEC 1
J 0
(-950 875);
DISPLAY 0.680851 (-950 875);
DISPLAY INVISIBLE (-950 875);
FORCEPROP 1 LASTPIN (-1300 825) $PN 1
J 0
(-1288 837);
DISPLAY 0.787234 (-1288 837);
PAINT MONO (-1288 837);
FORCEPROP 1 LASTPIN (-1100 825) $PN 2
J 0
(-1138 837);
DISPLAY 0.787234 (-1138 837);
PAINT MONO (-1138 837);
FORCEPROP 1 LAST PACK_TYPE 0402LF
J 0
(-1375 775);
DISPLAY 0.723404 (-1375 775);
FORCEPROP 1 LAST MATERIAL CHIP
J 0
(-1125 775);
DISPLAY 0.723404 (-1125 775);
FORCEPROP 1 LAST VALUE 33.2
J 2
(-950 825);
DISPLAY 0.723404 (-950 825);
FORCEPROP 1 LAST TOLERANCE 1%
J 0
(-725 825);
DISPLAY 0.723404 (-725 825);
PAINT SKYBLUE (-725 825);
DISPLAY INVISIBLE (-725 825);
FORCEPROP 1 LAST WATTAGE 1/16W
J 2
(-800 775);
DISPLAY 0.723404 (-800 775);
PAINT SKYBLUE (-800 775);
DISPLAY INVISIBLE (-800 775);
FORCEPROP 2 LAST CDS_LIB pure_quanta
J 0
(-1200 825);
DISPLAY INVISIBLE (-1200 825);
FORCEPROP 1 LAST PATH I17
J 0
(-1250 975);
DISPLAY 0.978723 (-1250 975);
PAINT WHITE (-1250 975);
DISPLAY INVISIBLE (-1250 975);
FORCEPROP 1 LAST PART_NUMBER CS03322FB03
J 0
(-1600 725);
DISPLAY 0.723404 (-1600 725);
PAINT WHITE (-1600 725);
DISPLAY INVISIBLE (-1600 725);
FORCEADD Q_RES..1
(-1525 1575);
FORCEPROP 1 LAST LOCATION R1166
J 0
(-1575 1625);
DISPLAY 0.978723 (-1575 1625);
FORCEPROP 0 LAST $SEC 1
J 0
(-1575 1675);
DISPLAY 0.680851 (-1575 1675);
PAINT MONO (-1575 1675);
DISPLAY INVISIBLE (-1575 1675);
FORCEPROP 0 LAST CDS_SEC 1
J 0
(-1575 1675);
DISPLAY 0.680851 (-1575 1675);
DISPLAY INVISIBLE (-1575 1675);
FORCEPROP 1 LASTPIN (-1625 1575) $PN 1
J 0
(-1613 1587);
DISPLAY 0.787234 (-1613 1587);
PAINT MONO (-1613 1587);
FORCEPROP 1 LASTPIN (-1425 1575) $PN 2
J 0
(-1463 1587);
DISPLAY 0.787234 (-1463 1587);
PAINT MONO (-1463 1587);
FORCEPROP 1 LAST PACK_TYPE 0402LF
J 0
(-1275 1575);
DISPLAY 0.510638 (-1275 1575);
FORCEPROP 1 LAST WATTAGE 1/16W
J 2
(-1325 1500);
DISPLAY 0.510638 (-1325 1500);
FORCEPROP 1 LAST TOLERANCE 5%
J 0
(-1350 1575);
DISPLAY 0.510638 (-1350 1575);
FORCEPROP 1 LAST VALUE 0
J 2
(-1375 1575);
DISPLAY 0.510638 (-1375 1575);
FORCEPROP 1 LAST MATERIAL CHIP
J 0
(-1600 1500);
DISPLAY 0.510638 (-1600 1500);
PAINT RED (-1600 1500);
FORCEPROP 2 LAST CDS_LIB pure_quanta
J 0
(-1525 1575);
DISPLAY INVISIBLE (-1525 1575);
FORCEPROP 1 LAST PATH I18
J 0
(-1575 1725);
DISPLAY 0.978723 (-1575 1725);
PAINT WHITE (-1575 1725);
DISPLAY INVISIBLE (-1575 1725);
FORCEPROP 1 LAST PART_NUMBER CS00002JB13
J 0
(-1600 1525);
DISPLAY 0.510638 (-1600 1525);
DISPLAY INVISIBLE (-1600 1525);
FORCEADD Q_RES..2
R 2
(-1075 1925);
FORCEPROP 1 LAST LOCATION R1167
J 2
(-1120 2050);
DISPLAY 0.638298 (-1120 2050);
FORCEPROP 0 LAST $SEC 1
J 0
(-1100 2100);
DISPLAY 0.680851 (-1100 2100);
PAINT MONO (-1100 2100);
DISPLAY INVISIBLE (-1100 2100);
FORCEPROP 0 LAST CDS_SEC 1
J 0
(-1100 2100);
DISPLAY 0.680851 (-1100 2100);
DISPLAY INVISIBLE (-1100 2100);
FORCEPROP 1 LASTPIN (-1075 2025) $PN 1
J 2
(-1080 1987);
DISPLAY 0.787234 (-1080 1987);
PAINT MONO (-1080 1987);
FORCEPROP 1 LASTPIN (-1075 1825) $PN 2
J 2
(-1080 1835);
DISPLAY 0.787234 (-1080 1835);
PAINT MONO (-1080 1835);
FORCEPROP 1 LAST TOLERANCE 1%
J 2
(-1120 1950);
DISPLAY 0.638298 (-1120 1950);
FORCEPROP 1 LAST WATTAGE 1/16W
J 2
(-1115 1900);
DISPLAY 0.638298 (-1115 1900);
FORCEPROP 1 LAST PACK_TYPE 0402LF
J 2
(-1115 1750);
DISPLAY 0.638298 (-1115 1750);
FORCEPROP 1 LAST MATERIAL CHIP
J 2
(-1115 1850);
DISPLAY 0.638298 (-1115 1850);
FORCEPROP 1 LAST VALUE 1K
J 2
(-1120 2000);
DISPLAY 0.638298 (-1120 2000);
FORCEPROP 2 LAST CDS_LIB pure_quanta
J 0
(-1075 1925);
DISPLAY INVISIBLE (-1075 1925);
FORCEPROP 1 LAST PATH I19
J 2
(-1125 2100);
DISPLAY 0.978723 (-1125 2100);
PAINT WHITE (-1125 2100);
DISPLAY INVISIBLE (-1125 2100);
FORCEPROP 1 LAST PART_NUMBER CS21002FB06
J 2
(-1115 1800);
DISPLAY 0.638298 (-1115 1800);
DISPLAY INVISIBLE (-1115 1800);
FORCEADD OFFPAGE..1
(-2175 -550);
PAINT AQUA (-2175 -550);
FORCEPROP 2 LAST $XR0 80 
J 0
(-2396 -550);
DISPLAY 0.638298 (-2396 -550);
PAINT MONO (-2396 -550);
FORCEPROP 2 LAST CDS_LIB standard
J 0
(-2175 -550);
DISPLAY INVISIBLE (-2175 -550);
FORCEPROP 1 LAST OFFPAGE TRUE
J 0
(-1850 -675);
DISPLAY 0.872340 (-1850 -675);
PAINT AQUA (-1850 -675);
DISPLAY INVISIBLE (-1850 -675);
FORCEPROP 1 LAST COMMENT_BODY TRUE
J 0
(-2050 -650);
DISPLAY 0.872340 (-2050 -650);
PAINT GREEN (-2050 -650);
DISPLAY INVISIBLE (-2050 -650);
FORCEPROP 2 LAST PATH I2
J 0
(-2375 -500);
DISPLAY 0.680851 (-2375 -500);
DISPLAY INVISIBLE (-2375 -500);
FORCEADD UNIVERSAL_POWER..1
R 2
(-1075 2175);
FORCEPROP 3 LASTPIN (-1075 2125) SIG_NAME P3V3_AUX\g
J 0
(-1065 2135);
DISPLAY 0.659574 (-1065 2135);
PAINT MONO (-1065 2135);
DISPLAY INVISIBLE (-1065 2135);
FORCEPROP 1 LAST HDL_POWER P3V3_AUX
J 1
(-1075 2225);
DISPLAY 0.723404 (-1075 2225);
PAINT GREEN (-1075 2225);
FORCEPROP 2 LAST CDS_LIB pure_quanta_power
J 0
(-1075 2175);
DISPLAY INVISIBLE (-1075 2175);
FORCEPROP 1 LAST PATH I20
J 2
(-1125 2200);
DISPLAY 0.872340 (-1125 2200);
PAINT AQUA (-1125 2200);
DISPLAY INVISIBLE (-1125 2200);
FORCEADD OFFPAGE..2
(-350 1575);
PAINT AQUA (-350 1575);
FORCEPROP 2 LAST $XR0 80 
J 0
(-161 1575);
DISPLAY 0.638298 (-161 1575);
PAINT MONO (-161 1575);
FORCEPROP 2 LAST CDS_LIB standard
J 0
(-350 1575);
DISPLAY INVISIBLE (-350 1575);
FORCEPROP 1 LAST OFFPAGE TRUE
J 0
(-25 1450);
DISPLAY 0.872340 (-25 1450);
PAINT AQUA (-25 1450);
DISPLAY INVISIBLE (-25 1450);
FORCEPROP 1 LAST COMMENT_BODY TRUE
J 0
(-395 1480);
DISPLAY 0.872340 (-395 1480);
PAINT GREEN (-395 1480);
DISPLAY INVISIBLE (-395 1480);
FORCEPROP 2 LAST PATH I21
J 0
(-175 1650);
DISPLAY 0.680851 (-175 1650);
DISPLAY INVISIBLE (-175 1650);
FORCEADD OFFPAGE..1
(-5200 2975);
PAINT AQUA (-5200 2975);
FORCEPROP 2 LAST $XR0 140 
J 0
(-5452 2975);
DISPLAY 0.638298 (-5452 2975);
PAINT MONO (-5452 2975);
FORCEPROP 2 LAST CDS_LIB standard
J 0
(-5200 2975);
DISPLAY INVISIBLE (-5200 2975);
FORCEPROP 1 LAST OFFPAGE TRUE
J 0
(-4875 2850);
DISPLAY 0.872340 (-4875 2850);
PAINT AQUA (-4875 2850);
DISPLAY INVISIBLE (-4875 2850);
FORCEPROP 1 LAST COMMENT_BODY TRUE
J 0
(-5075 2875);
DISPLAY 0.872340 (-5075 2875);
PAINT GREEN (-5075 2875);
DISPLAY INVISIBLE (-5075 2875);
FORCEPROP 2 LAST PATH I22
J 0
(-5150 3050);
DISPLAY 0.680851 (-5150 3050);
DISPLAY INVISIBLE (-5150 3050);
FORCEADD UNIVERSAL_GND..1
(-4075 2525);
FORCEPROP 3 LASTPIN (-4075 2575) SIG_NAME GND\g
J 0
(-4065 2585);
DISPLAY 0.659574 (-4065 2585);
PAINT MONO (-4065 2585);
DISPLAY INVISIBLE (-4065 2585);
FORCEPROP 2 LAST CDS_LIB pure_quanta_power
J 0
(-4075 2525);
DISPLAY INVISIBLE (-4075 2525);
FORCEPROP 1 LAST HDL_POWER GND
J 1
(-4050 2450);
DISPLAY 0.872340 (-4050 2450);
PAINT GREEN (-4050 2450);
DISPLAY INVISIBLE (-4050 2450);
FORCEPROP 1 LAST PATH I23
J 0
(-4000 2525);
DISPLAY 0.872340 (-4000 2525);
PAINT AQUA (-4000 2525);
DISPLAY INVISIBLE (-4000 2525);
FORCEADD MOSFET_N..1
(-4125 3075);
FORCEPROP 1 LAST LOCATION U32
J 0
(-3953 2766);
DISPLAY 0.723404 (-3953 2766);
PAINT GREEN (-3953 2766);
FORCEPROP 0 LAST $SEC 1
J 0
(-3950 3000);
DISPLAY 0.680851 (-3950 3000);
PAINT MONO (-3950 3000);
DISPLAY INVISIBLE (-3950 3000);
FORCEPROP 0 LAST CDS_SEC 1
J 0
(-3950 3000);
DISPLAY 0.680851 (-3950 3000);
DISPLAY INVISIBLE (-3950 3000);
FORCEPROP 1 LASTPIN (-4075 3175) $PN D
R 1
J 0
(-4075 3168);
DISPLAY 0.659574 (-4075 3168);
PAINT MONO (-4075 3168);
FORCEPROP 1 LASTPIN (-4225 2975) $PN G
J 2
(-4215 2978);
DISPLAY 0.659574 (-4215 2978);
PAINT MONO (-4215 2978);
FORCEPROP 1 LASTPIN (-4075 2875) $PN S
R 1
J 2
(-4075 2888);
DISPLAY 0.659574 (-4075 2888);
PAINT MONO (-4075 2888);
FORCEPROP 1 LAST MATERIAL IC
J 0
(-3953 2606);
DISPLAY 0.723404 (-3953 2606);
PAINT GREEN (-3953 2606);
FORCEPROP 2 LAST MANUF_PN BSS138K
J 0
(-3950 2950);
DISPLAY 0.680851 (-3950 2950);
FORCEPROP 1 LAST VALUE BSS138K
J 0
(-3953 2846);
DISPLAY 0.723404 (-3953 2846);
PAINT GREEN (-3953 2846);
FORCEPROP 2 LAST PATH I24
J 0
(-3950 3000);
DISPLAY 0.680851 (-3950 3000);
FORCEPROP 1 LAST PACK_TYPE SMLF
J 0
(-4100 2825);
DISPLAY 0.723404 (-4100 2825);
PAINT GREEN (-4100 2825);
DISPLAY INVISIBLE (-4100 2825);
FORCEPROP 2 LAST CDS_LIB pure_quanta
J 0
(-4125 3075);
DISPLAY INVISIBLE (-4125 3075);
FORCEPROP 1 LAST CDS_LMAN_SYM_OUTLINE -50,50,100,-150
J 0
(-4125 3075);
DISPLAY 0.468085 (-4125 3075);
PAINT GREEN (-4125 3075);
DISPLAY INVISIBLE (-4125 3075);
FORCEPROP 1 LAST PART_NUMBER BAM138K0000
J 0
(-3953 2686);
DISPLAY 0.723404 (-3953 2686);
PAINT GREEN (-3953 2686);
DISPLAY INVISIBLE (-3953 2686);
FORCEADD Q_RES..2
R 2
(-4075 3625);
FORCEPROP 1 LAST LOCATION R1149
J 2
(-4120 3750);
DISPLAY 0.978723 (-4120 3750);
FORCEPROP 0 LAST $SEC 1
J 0
(-4100 3800);
DISPLAY 0.680851 (-4100 3800);
PAINT MONO (-4100 3800);
DISPLAY INVISIBLE (-4100 3800);
FORCEPROP 0 LAST CDS_SEC 1
J 0
(-4100 3800);
DISPLAY 0.680851 (-4100 3800);
DISPLAY INVISIBLE (-4100 3800);
FORCEPROP 1 LASTPIN (-4075 3725) $PN 1
J 2
(-4080 3687);
DISPLAY 0.787234 (-4080 3687);
PAINT MONO (-4080 3687);
FORCEPROP 1 LASTPIN (-4075 3525) $PN 2
J 2
(-4080 3535);
DISPLAY 0.787234 (-4080 3535);
PAINT MONO (-4080 3535);
FORCEPROP 1 LAST TOLERANCE 1%
J 2
(-4120 3650);
DISPLAY 0.978723 (-4120 3650);
FORCEPROP 1 LAST VALUE 1K
J 2
(-4120 3700);
DISPLAY 0.978723 (-4120 3700);
FORCEPROP 1 LAST MATERIAL CHIP
J 2
(-4115 3550);
DISPLAY 0.978723 (-4115 3550);
FORCEPROP 1 LAST WATTAGE 1/16W
J 2
(-4115 3600);
DISPLAY 0.978723 (-4115 3600);
FORCEPROP 1 LAST PACK_TYPE 0402LF
J 2
(-4115 3450);
DISPLAY 0.978723 (-4115 3450);
FORCEPROP 2 LAST CDS_LIB pure_quanta
J 2
(-4075 3625);
DISPLAY INVISIBLE (-4075 3625);
FORCEPROP 1 LAST PATH I25
J 2
(-4125 3800);
DISPLAY 0.978723 (-4125 3800);
PAINT WHITE (-4125 3800);
DISPLAY INVISIBLE (-4125 3800);
FORCEPROP 1 LAST PART_NUMBER CS21002FB06
J 2
(-4115 3500);
DISPLAY 0.978723 (-4115 3500);
DISPLAY INVISIBLE (-4115 3500);
FORCEADD UNIVERSAL_POWER..1
R 2
(-4075 4025);
FORCEPROP 3 LASTPIN (-4075 3975) SIG_NAME P3V3_AUX\g
J 0
(-4065 3985);
DISPLAY 0.659574 (-4065 3985);
PAINT MONO (-4065 3985);
DISPLAY INVISIBLE (-4065 3985);
FORCEPROP 1 LAST HDL_POWER P3V3_AUX
J 1
(-4075 4075);
DISPLAY 0.723404 (-4075 4075);
PAINT GREEN (-4075 4075);
FORCEPROP 2 LAST CDS_LIB pure_quanta_power
J 0
(-4075 4025);
DISPLAY INVISIBLE (-4075 4025);
FORCEPROP 1 LAST PATH I26
J 2
(-4125 4050);
DISPLAY 0.872340 (-4125 4050);
PAINT AQUA (-4125 4050);
DISPLAY INVISIBLE (-4125 4050);
FORCEADD OFFPAGE..1
(-3250 3425);
PAINT AQUA (-3250 3425);
FORCEPROP 2 LAST $XR3 141 
J 0
(-3831 3425);
DISPLAY 0.638298 (-3831 3425);
PAINT MONO (-3831 3425);
FORCEPROP 2 LAST $XR2 140 
J 0
(-3711 3425);
DISPLAY 0.638298 (-3711 3425);
PAINT MONO (-3711 3425);
FORCEPROP 2 LAST $XR1 83 
J 0
(-3591 3425);
DISPLAY 0.638298 (-3591 3425);
PAINT MONO (-3591 3425);
FORCEPROP 2 LAST $XR0 81 
J 0
(-3501 3425);
DISPLAY 0.638298 (-3501 3425);
PAINT MONO (-3501 3425);
FORCEPROP 2 LAST CDS_LIB standard
J 0
(-3250 3425);
DISPLAY INVISIBLE (-3250 3425);
FORCEPROP 1 LAST OFFPAGE TRUE
J 0
(-2925 3300);
DISPLAY 0.872340 (-2925 3300);
PAINT AQUA (-2925 3300);
DISPLAY INVISIBLE (-2925 3300);
FORCEPROP 1 LAST COMMENT_BODY TRUE
J 0
(-3125 3325);
DISPLAY 0.872340 (-3125 3325);
PAINT GREEN (-3125 3325);
DISPLAY INVISIBLE (-3125 3325);
FORCEPROP 2 LAST PATH I27
J 0
(-3200 3500);
DISPLAY 0.680851 (-3200 3500);
DISPLAY INVISIBLE (-3200 3500);
FORCEADD Q_RES..1
(-2325 3425);
FORCEPROP 1 LAST LOCATION R1164
J 0
(-2375 3450);
DISPLAY 0.638298 (-2375 3450);
FORCEPROP 0 LAST $SEC 1
J 0
(-2375 3500);
DISPLAY 0.680851 (-2375 3500);
PAINT MONO (-2375 3500);
DISPLAY INVISIBLE (-2375 3500);
FORCEPROP 0 LAST CDS_SEC 1
J 0
(-2375 3500);
DISPLAY 0.680851 (-2375 3500);
DISPLAY INVISIBLE (-2375 3500);
FORCEPROP 1 LASTPIN (-2425 3425) $PN 1
J 0
(-2413 3437);
DISPLAY 0.787234 (-2413 3437);
PAINT MONO (-2413 3437);
FORCEPROP 1 LASTPIN (-2225 3425) $PN 2
J 0
(-2263 3437);
DISPLAY 0.787234 (-2263 3437);
PAINT MONO (-2263 3437);
FORCEPROP 1 LAST VALUE 0
J 2
(-2175 3425);
DISPLAY 0.510638 (-2175 3425);
FORCEPROP 1 LAST TOLERANCE 5%
J 0
(-2150 3425);
DISPLAY 0.510638 (-2150 3425);
FORCEPROP 1 LAST MATERIAL EMPTY
J 0
(-2525 3425);
DISPLAY 0.510638 (-2525 3425);
PAINT RED (-2525 3425);
FORCEPROP 2 LAST CDS_LIB pure_quanta
J 0
(-2325 3425);
DISPLAY INVISIBLE (-2325 3425);
FORCEPROP 1 LAST PACK_TYPE 0402LF
J 0
(-2075 3425);
DISPLAY 0.510638 (-2075 3425);
DISPLAY INVISIBLE (-2075 3425);
FORCEPROP 1 LAST WATTAGE 1/16W
J 2
(-2225 3350);
DISPLAY 0.319149 (-2225 3350);
DISPLAY INVISIBLE (-2225 3350);
FORCEPROP 1 LAST PATH I28
J 0
(-2375 3575);
DISPLAY 0.978723 (-2375 3575);
PAINT WHITE (-2375 3575);
DISPLAY INVISIBLE (-2375 3575);
FORCEPROP 1 LAST PART_NUMBER CS00002JB13
J 0
(-2400 3375);
DISPLAY 0.319149 (-2400 3375);
DISPLAY INVISIBLE (-2400 3375);
FORCEADD OFFPAGE..1
(-1450 2350);
PAINT AQUA (-1450 2350);
FORCEPROP 2 LAST $XR1 142 
J 0
(-1852 2350);
DISPLAY 0.638298 (-1852 2350);
PAINT MONO (-1852 2350);
FORCEPROP 2 LAST $XR0 140 
J 0
(-1732 2350);
DISPLAY 0.638298 (-1732 2350);
PAINT MONO (-1732 2350);
FORCEPROP 2 LAST CDS_LIB standard
J 0
(-1450 2350);
DISPLAY INVISIBLE (-1450 2350);
FORCEPROP 1 LAST OFFPAGE TRUE
J 0
(-1125 2225);
DISPLAY 0.872340 (-1125 2225);
PAINT AQUA (-1125 2225);
DISPLAY INVISIBLE (-1125 2225);
FORCEPROP 1 LAST COMMENT_BODY TRUE
J 0
(-1325 2250);
DISPLAY 0.872340 (-1325 2250);
PAINT GREEN (-1325 2250);
DISPLAY INVISIBLE (-1325 2250);
FORCEPROP 2 LAST PATH I29
J 0
(-1400 2425);
DISPLAY 0.680851 (-1400 2425);
DISPLAY INVISIBLE (-1400 2425);
FORCEADD Q_RES..1
(-4000 1575);
FORCEPROP 1 LAST LOCATION R1163
J 0
(-4050 1625);
DISPLAY 0.978723 (-4050 1625);
FORCEPROP 0 LAST $SEC 1
J 0
(-4050 1675);
DISPLAY 0.680851 (-4050 1675);
PAINT MONO (-4050 1675);
DISPLAY INVISIBLE (-4050 1675);
FORCEPROP 0 LAST CDS_SEC 1
J 0
(-4050 1675);
DISPLAY 0.680851 (-4050 1675);
DISPLAY INVISIBLE (-4050 1675);
FORCEPROP 1 LASTPIN (-4100 1575) $PN 1
J 0
(-4088 1587);
DISPLAY 0.787234 (-4088 1587);
PAINT MONO (-4088 1587);
FORCEPROP 1 LASTPIN (-3900 1575) $PN 2
J 0
(-3938 1587);
DISPLAY 0.787234 (-3938 1587);
PAINT MONO (-3938 1587);
FORCEPROP 1 LAST TOLERANCE 5%
J 0
(-3825 1575);
DISPLAY 0.510638 (-3825 1575);
FORCEPROP 1 LAST PACK_TYPE 0402LF
J 0
(-3750 1575);
DISPLAY 0.510638 (-3750 1575);
FORCEPROP 1 LAST VALUE 0
J 2
(-3850 1575);
DISPLAY 0.510638 (-3850 1575);
FORCEPROP 1 LAST MATERIAL CHIP
J 0
(-4075 1500);
DISPLAY 0.510638 (-4075 1500);
PAINT RED (-4075 1500);
FORCEPROP 1 LAST WATTAGE 1/16W
J 2
(-3800 1500);
DISPLAY 0.510638 (-3800 1500);
FORCEPROP 2 LAST CDS_LIB pure_quanta
J 0
(-4000 1575);
DISPLAY INVISIBLE (-4000 1575);
FORCEPROP 1 LAST PATH I3
J 0
(-4050 1725);
DISPLAY 0.978723 (-4050 1725);
PAINT WHITE (-4050 1725);
DISPLAY INVISIBLE (-4050 1725);
FORCEPROP 1 LAST PART_NUMBER CS00002JB13
J 0
(-4075 1525);
DISPLAY 0.510638 (-4075 1525);
DISPLAY INVISIBLE (-4075 1525);
FORCEADD UNIVERSAL_GND..1
(-1525 2950);
FORCEPROP 3 LASTPIN (-1525 3000) SIG_NAME GND\g
J 0
(-1515 3010);
DISPLAY 0.659574 (-1515 3010);
PAINT MONO (-1515 3010);
DISPLAY INVISIBLE (-1515 3010);
FORCEPROP 2 LAST CDS_LIB pure_quanta_power
J 0
(-1525 2950);
DISPLAY INVISIBLE (-1525 2950);
FORCEPROP 1 LAST HDL_POWER GND
J 1
(-1500 2875);
DISPLAY 0.872340 (-1500 2875);
PAINT GREEN (-1500 2875);
DISPLAY INVISIBLE (-1500 2875);
FORCEPROP 1 LAST PATH I30
J 0
(-1450 2950);
DISPLAY 0.872340 (-1450 2950);
PAINT AQUA (-1450 2950);
DISPLAY INVISIBLE (-1450 2950);
FORCEADD 74LVC1G08W57..1
(-950 3325);
FORCEPROP 1 LAST LOCATION U31
J 0
(-1094 3756);
DISPLAY 0.723404 (-1094 3756);
PAINT GREEN (-1094 3756);
FORCEPROP 2 LAST SEC 1
J 0
(-1075 3800);
DISPLAY 0.680851 (-1075 3800);
PAINT MONO (-1075 3800);
DISPLAY INVISIBLE (-1075 3800);
FORCEPROP 2 LASTPIN (-1250 3425) $PN 1
J 2
(-1260 3435);
DISPLAY 0.680851 (-1260 3435);
PAINT MONO (-1260 3435);
FORCEPROP 2 LASTPIN (-1250 3325) $PN 2
J 2
(-1260 3335);
DISPLAY 0.680851 (-1260 3335);
PAINT MONO (-1260 3335);
FORCEPROP 2 LASTPIN (-1250 3225) $PN 3
J 2
(-1260 3235);
DISPLAY 0.680851 (-1260 3235);
PAINT MONO (-1260 3235);
FORCEPROP 2 LASTPIN (-650 3425) $PN 5
J 0
(-640 3435);
DISPLAY 0.680851 (-640 3435);
PAINT MONO (-640 3435);
FORCEPROP 2 LASTPIN (-650 3275) $PN 4
J 0
(-640 3285);
DISPLAY 0.680851 (-640 3285);
PAINT MONO (-640 3285);
FORCEPROP 2 LAST PART_TYPE SMLF
J 0
(-1100 3650);
DISPLAY 0.808511 (-1100 3650);
FORCEPROP 1 LAST MATERIAL IC
J 0
(-1094 3482);
DISPLAY 0.723404 (-1094 3482);
PAINT GREEN (-1094 3482);
FORCEPROP 2 LAST VALUE 74LVC1G08W5-7
J 0
(-1100 3600);
DISPLAY 0.808511 (-1100 3600);
FORCEPROP 1 LAST NEEDS_NO_SIZE TRUE
J 0
(-950 3325);
DISPLAY 0.723404 (-950 3325);
PAINT GREEN (-950 3325);
DISPLAY INVISIBLE (-950 3325);
FORCEPROP 1 LAST CDS_LMAN_SYM_OUTLINE -150,150,150,-150
J 0
(-950 3325);
DISPLAY 0.468085 (-950 3325);
PAINT GREEN (-950 3325);
DISPLAY INVISIBLE (-950 3325);
FORCEPROP 2 LAST CDS_LIB pure_quanta
J 0
(-950 3325);
DISPLAY INVISIBLE (-950 3325);
FORCEPROP 2 LAST SEC_TYPE 
J 0
(-1075 3800);
DISPLAY 0.680851 (-1075 3800);
DISPLAY INVISIBLE (-1075 3800);
FORCEPROP 1 LAST PATH I31
J 0
(-950 3325);
DISPLAY 0.723404 (-950 3325);
PAINT GREEN (-950 3325);
DISPLAY INVISIBLE (-950 3325);
FORCEPROP 1 LAST PART_NUMBER AL1G0008020
J 0
(-1100 3550);
DISPLAY 0.723404 (-1100 3550);
PAINT GREEN (-1100 3550);
DISPLAY INVISIBLE (-1100 3550);
FORCEADD Q_RES..2
R 2
(-1425 3850);
FORCEPROP 1 LAST LOCATION R1165
J 2
(-1470 3975);
DISPLAY 0.978723 (-1470 3975);
FORCEPROP 0 LAST $SEC 1
J 0
(-1450 4025);
DISPLAY 0.680851 (-1450 4025);
PAINT MONO (-1450 4025);
DISPLAY INVISIBLE (-1450 4025);
FORCEPROP 0 LAST CDS_SEC 1
J 0
(-1450 4025);
DISPLAY 0.680851 (-1450 4025);
DISPLAY INVISIBLE (-1450 4025);
FORCEPROP 1 LASTPIN (-1425 3950) $PN 1
J 2
(-1430 3912);
DISPLAY 0.787234 (-1430 3912);
PAINT MONO (-1430 3912);
FORCEPROP 1 LASTPIN (-1425 3750) $PN 2
J 2
(-1430 3760);
DISPLAY 0.787234 (-1430 3760);
PAINT MONO (-1430 3760);
FORCEPROP 1 LAST PACK_TYPE 0402LF
J 2
(-1465 3675);
DISPLAY 0.978723 (-1465 3675);
FORCEPROP 1 LAST VALUE 1K
J 2
(-1470 3925);
DISPLAY 0.978723 (-1470 3925);
FORCEPROP 1 LAST TOLERANCE 1%
J 2
(-1470 3875);
DISPLAY 0.978723 (-1470 3875);
FORCEPROP 1 LAST WATTAGE 1/16W
J 2
(-1465 3825);
DISPLAY 0.978723 (-1465 3825);
FORCEPROP 1 LAST MATERIAL CHIP
J 2
(-1465 3775);
DISPLAY 0.978723 (-1465 3775);
FORCEPROP 2 LAST CDS_LIB pure_quanta
J 0
(-1425 3850);
DISPLAY INVISIBLE (-1425 3850);
FORCEPROP 1 LAST PATH I32
J 2
(-1475 4025);
DISPLAY 0.978723 (-1475 4025);
PAINT WHITE (-1475 4025);
DISPLAY INVISIBLE (-1475 4025);
FORCEPROP 1 LAST PART_NUMBER CS21002FB06
J 2
(-1465 3725);
DISPLAY 0.978723 (-1465 3725);
DISPLAY INVISIBLE (-1465 3725);
FORCEADD UNIVERSAL_POWER..1
R 2
(-1425 4250);
FORCEPROP 3 LASTPIN (-1425 4200) SIG_NAME P3V3_AUX\g
J 0
(-1415 4210);
DISPLAY 0.659574 (-1415 4210);
PAINT MONO (-1415 4210);
DISPLAY INVISIBLE (-1415 4210);
FORCEPROP 1 LAST HDL_POWER P3V3_AUX
J 1
(-1425 4300);
DISPLAY 0.723404 (-1425 4300);
PAINT GREEN (-1425 4300);
FORCEPROP 2 LAST CDS_LIB pure_quanta_power
J 0
(-1425 4250);
DISPLAY INVISIBLE (-1425 4250);
FORCEPROP 1 LAST PATH I33
J 2
(-1475 4275);
DISPLAY 0.872340 (-1475 4275);
PAINT AQUA (-1475 4275);
DISPLAY INVISIBLE (-1475 4275);
FORCEADD Q_RES..1
(-650 2350);
FORCEPROP 1 LAST LOCATION R1169
J 0
(-700 2400);
DISPLAY 0.978723 (-700 2400);
FORCEPROP 0 LAST $SEC 1
J 0
(-700 2450);
DISPLAY 0.680851 (-700 2450);
PAINT MONO (-700 2450);
DISPLAY INVISIBLE (-700 2450);
FORCEPROP 0 LAST CDS_SEC 1
J 0
(-700 2450);
DISPLAY 0.680851 (-700 2450);
DISPLAY INVISIBLE (-700 2450);
FORCEPROP 1 LASTPIN (-750 2350) $PN 1
J 0
(-738 2362);
DISPLAY 0.787234 (-738 2362);
PAINT MONO (-738 2362);
FORCEPROP 1 LASTPIN (-550 2350) $PN 2
J 0
(-588 2362);
DISPLAY 0.787234 (-588 2362);
PAINT MONO (-588 2362);
FORCEPROP 1 LAST WATTAGE 1/16W
J 2
(-450 2275);
DISPLAY 0.510638 (-450 2275);
FORCEPROP 1 LAST MATERIAL CHIP
J 0
(-725 2275);
DISPLAY 0.510638 (-725 2275);
PAINT RED (-725 2275);
FORCEPROP 1 LAST VALUE 0
J 2
(-500 2350);
DISPLAY 0.510638 (-500 2350);
FORCEPROP 1 LAST TOLERANCE 5%
J 0
(-475 2350);
DISPLAY 0.510638 (-475 2350);
FORCEPROP 1 LAST PACK_TYPE 0402LF
J 0
(-400 2350);
DISPLAY 0.510638 (-400 2350);
FORCEPROP 2 LAST CDS_LIB pure_quanta
J 0
(-650 2350);
DISPLAY INVISIBLE (-650 2350);
FORCEPROP 1 LAST PATH I34
J 0
(-700 2500);
DISPLAY 0.978723 (-700 2500);
PAINT WHITE (-700 2500);
DISPLAY INVISIBLE (-700 2500);
FORCEPROP 1 LAST PART_NUMBER CS00002JB13
J 0
(-725 2300);
DISPLAY 0.510638 (-725 2300);
DISPLAY INVISIBLE (-725 2300);
FORCEADD UNIVERSAL_GND..1
(-350 3375);
FORCEPROP 3 LASTPIN (-350 3425) SIG_NAME GND\g
J 0
(-340 3435);
DISPLAY 0.659574 (-340 3435);
PAINT MONO (-340 3435);
DISPLAY INVISIBLE (-340 3435);
FORCEPROP 2 LAST CDS_LIB pure_quanta_power
J 0
(-350 3375);
DISPLAY INVISIBLE (-350 3375);
FORCEPROP 1 LAST HDL_POWER GND
J 1
(-325 3300);
DISPLAY 0.872340 (-325 3300);
PAINT GREEN (-325 3300);
DISPLAY INVISIBLE (-325 3300);
FORCEPROP 1 LAST PATH I35
J 0
(-275 3375);
DISPLAY 0.872340 (-275 3375);
PAINT AQUA (-275 3375);
DISPLAY INVISIBLE (-275 3375);
FORCEADD Q_CAP..1
(-350 3675);
FORCEPROP 1 LAST LOCATION C1062
J 0
(-300 3825);
DISPLAY 0.787234 (-300 3825);
FORCEPROP 0 LAST $SEC 1
J 0
(-300 3875);
DISPLAY 0.680851 (-300 3875);
PAINT MONO (-300 3875);
DISPLAY INVISIBLE (-300 3875);
FORCEPROP 0 LAST CDS_SEC 1
J 0
(-300 3875);
DISPLAY 0.680851 (-300 3875);
DISPLAY INVISIBLE (-300 3875);
FORCEPROP 1 LASTPIN (-350 3775) $PN 1
J 0
(-340 3755);
DISPLAY 0.787234 (-340 3755);
PAINT MONO (-340 3755);
FORCEPROP 1 LASTPIN (-350 3575) $PN 2
J 0
(-340 3555);
DISPLAY 0.787234 (-340 3555);
PAINT MONO (-340 3555);
FORCEPROP 1 LAST VALUE 0.1UF
J 0
(-300 3775);
DISPLAY 0.787234 (-300 3775);
FORCEPROP 1 LAST VOLTAGE 25V
J 0
(-300 3725);
DISPLAY 0.787234 (-300 3725);
FORCEPROP 1 LAST PACK_TYPE 0402
J 0
(-300 3525);
DISPLAY 0.787234 (-300 3525);
FORCEPROP 1 LAST MATERIAL X7R
J 0
(-300 3625);
DISPLAY 0.787234 (-300 3625);
PAINT RED (-300 3625);
FORCEPROP 1 LAST TOLERANCE 10%
J 0
(-300 3675);
DISPLAY 0.787234 (-300 3675);
FORCEPROP 2 LAST CDS_LIB pure_quanta
J 0
(-350 3675);
DISPLAY INVISIBLE (-350 3675);
FORCEPROP 1 LAST PATH I36
J 0
(-300 3825);
DISPLAY 0.978723 (-300 3825);
PAINT WHITE (-300 3825);
DISPLAY INVISIBLE (-300 3825);
FORCEPROP 1 LAST PART_NUMBER CH4104K1B00
J 0
(-300 3575);
DISPLAY 0.787234 (-300 3575);
DISPLAY INVISIBLE (-300 3575);
FORCEADD UNIVERSAL_POWER..1
R 2
(-350 3950);
FORCEPROP 3 LASTPIN (-350 3900) SIG_NAME P3V3_AUX\g
J 0
(-340 3910);
DISPLAY 0.659574 (-340 3910);
PAINT MONO (-340 3910);
DISPLAY INVISIBLE (-340 3910);
FORCEPROP 1 LAST HDL_POWER P3V3_AUX
J 1
(-350 4000);
DISPLAY 0.723404 (-350 4000);
PAINT GREEN (-350 4000);
FORCEPROP 2 LAST CDS_LIB pure_quanta_power
J 0
(-350 3950);
DISPLAY INVISIBLE (-350 3950);
FORCEPROP 1 LAST PATH I37
J 2
(-400 3975);
DISPLAY 0.872340 (-400 3975);
PAINT AQUA (-400 3975);
DISPLAY INVISIBLE (-400 3975);
FORCEADD UNIVERSAL_GND..1
(-50 -775);
FORCEPROP 3 LASTPIN (-50 -725) SIG_NAME GND\g
J 0
(-40 -715);
DISPLAY 0.659574 (-40 -715);
PAINT MONO (-40 -715);
DISPLAY INVISIBLE (-40 -715);
FORCEPROP 2 LAST CDS_LIB pure_quanta_power
J 0
(-50 -775);
DISPLAY INVISIBLE (-50 -775);
FORCEPROP 1 LAST HDL_POWER GND
J 1
(-25 -850);
DISPLAY 0.872340 (-25 -850);
PAINT GREEN (-25 -850);
DISPLAY INVISIBLE (-25 -850);
FORCEPROP 1 LAST PATH I38
J 0
(25 -775);
DISPLAY 0.872340 (25 -775);
PAINT AQUA (25 -775);
DISPLAY INVISIBLE (25 -775);
FORCEADD Q_RES..1
R 2
(625 -1300);
FORCEPROP 1 LAST LOCATION R1147
J 2
(825 -1300);
DISPLAY 0.489362 (825 -1300);
PAINT SKYBLUE (825 -1300);
FORCEPROP 0 LAST $SEC 1
J 0
(825 -1275);
DISPLAY 0.680851 (825 -1275);
PAINT MONO (825 -1275);
DISPLAY INVISIBLE (825 -1275);
FORCEPROP 0 LAST CDS_SEC 1
J 0
(825 -1275);
DISPLAY 0.680851 (825 -1275);
DISPLAY INVISIBLE (825 -1275);
FORCEPROP 1 LASTPIN (725 -1300) $PN 1
J 2
(713 -1288);
DISPLAY 0.787234 (713 -1288);
PAINT MONO (713 -1288);
FORCEPROP 1 LASTPIN (525 -1300) $PN 2
J 2
(563 -1288);
DISPLAY 0.787234 (563 -1288);
PAINT MONO (563 -1288);
FORCEPROP 1 LAST MATERIAL EMPTY
J 0
(450 -1325);
DISPLAY 0.489362 (450 -1325);
PAINT RED (450 -1325);
FORCEPROP 1 LAST VALUE 0
J 0
(475 -1300);
DISPLAY 0.489362 (475 -1300);
PAINT SKYBLUE (475 -1300);
FORCEPROP 2 LAST CDS_LIB pure_quanta
J 0
(625 -1300);
DISPLAY INVISIBLE (625 -1300);
FORCEPROP 2 LAST BOM_COST MEM
J 0
(600 -1150);
DISPLAY 0.744681 (600 -1150);
PAINT WHITE (600 -1150);
DISPLAY INVISIBLE (600 -1150);
FORCEPROP 1 LAST WATTAGE 1/16W
J 0
(700 -1375);
DISPLAY 0.489362 (700 -1375);
PAINT SKYBLUE (700 -1375);
DISPLAY INVISIBLE (700 -1375);
FORCEPROP 1 LAST TOLERANCE 5%
J 2
(750 -1325);
DISPLAY 0.489362 (750 -1325);
PAINT SKYBLUE (750 -1325);
DISPLAY INVISIBLE (750 -1325);
FORCEPROP 1 LAST PACK_TYPE 0402LF
J 0
(450 -1375);
DISPLAY 0.489362 (450 -1375);
PAINT SKYBLUE (450 -1375);
DISPLAY INVISIBLE (450 -1375);
FORCEPROP 1 LAST PATH I39
J 2
(675 -1150);
DISPLAY 0.978723 (675 -1150);
PAINT WHITE (675 -1150);
DISPLAY INVISIBLE (675 -1150);
FORCEPROP 1 LAST PART_NUMBER CS00002JB13
J 0
(525 -1250);
DISPLAY 0.489362 (525 -1250);
PAINT SKYBLUE (525 -1250);
DISPLAY INVISIBLE (525 -1250);
FORCEADD UNIVERSAL_GND..1
(-3300 1775);
FORCEPROP 3 LASTPIN (-3300 1825) SIG_NAME GND\g
J 0
(-3290 1835);
DISPLAY 0.659574 (-3290 1835);
PAINT MONO (-3290 1835);
DISPLAY INVISIBLE (-3290 1835);
FORCEPROP 2 LAST CDS_LIB pure_quanta_power
J 0
(-3300 1775);
DISPLAY INVISIBLE (-3300 1775);
FORCEPROP 1 LAST HDL_POWER GND
J 1
(-3275 1700);
DISPLAY 0.872340 (-3275 1700);
PAINT GREEN (-3275 1700);
DISPLAY INVISIBLE (-3275 1700);
FORCEPROP 1 LAST PATH I4
J 0
(-3225 1775);
DISPLAY 0.872340 (-3225 1775);
PAINT AQUA (-3225 1775);
DISPLAY INVISIBLE (-3225 1775);
FORCEADD 74LVC1G32GW..1
(225 -500);
FORCEPROP 1 LAST LOCATION U37
J 0
(75 -245);
DISPLAY 0.723404 (75 -245);
PAINT GREEN (75 -245);
FORCEPROP 0 LAST $SEC 1
J 0
(75 -100);
DISPLAY 0.680851 (75 -100);
PAINT MONO (75 -100);
DISPLAY INVISIBLE (75 -100);
FORCEPROP 0 LAST CDS_SEC 1
J 0
(75 -100);
DISPLAY 0.680851 (75 -100);
DISPLAY INVISIBLE (75 -100);
FORCEPROP 0 LASTPIN (25 -600) $PN 3
J 2
(15 -590);
DISPLAY 0.680851 (15 -590);
PAINT MONO (15 -590);
FORCEPROP 0 LASTPIN (-75 -450) $PN 1
J 2
(-85 -440);
DISPLAY 0.680851 (-85 -440);
PAINT MONO (-85 -440);
FORCEPROP 0 LASTPIN (-75 -550) $PN 2
J 2
(-85 -540);
DISPLAY 0.680851 (-85 -540);
PAINT MONO (-85 -540);
FORCEPROP 0 LASTPIN (525 -500) $PN 4
J 0
(535 -490);
DISPLAY 0.680851 (535 -490);
PAINT MONO (535 -490);
FORCEPROP 0 LASTPIN (25 -400) $PN 5
J 2
(15 -390);
DISPLAY 0.680851 (15 -390);
PAINT MONO (15 -390);
FORCEPROP 1 LAST MATERIAL IC
J 0
(75 -365);
DISPLAY 0.723404 (75 -365);
PAINT GREEN (75 -365);
FORCEPROP 2 LAST PACK_TYPE SMLF
J 0
(75 -200);
DISPLAY 0.680851 (75 -200);
FORCEPROP 2 LAST VALUE 74LVC1G32GW
J 0
(75 -150);
DISPLAY 0.680851 (75 -150);
FORCEPROP 2 LAST CDS_LIB pure_quanta
J 0
(225 -500);
DISPLAY INVISIBLE (225 -500);
FORCEPROP 1 LAST NEEDS_NO_SIZE TRUE
J 0
(225 -500);
DISPLAY 0.468085 (225 -500);
PAINT GREEN (225 -500);
DISPLAY INVISIBLE (225 -500);
FORCEPROP 1 LAST PATH I40
J 0
(250 -370);
DISPLAY 0.723404 (250 -370);
PAINT GREEN (250 -370);
DISPLAY INVISIBLE (250 -370);
FORCEPROP 1 LAST PART_NUMBER ALVC1G32007
J 0
(75 -315);
DISPLAY 0.723404 (75 -315);
PAINT GREEN (75 -315);
DISPLAY INVISIBLE (75 -315);
FORCEADD Q_RES..1
R 2
(625 200);
FORCEPROP 1 LAST LOCATION R1146
J 2
(825 200);
DISPLAY 0.489362 (825 200);
PAINT SKYBLUE (825 200);
FORCEPROP 0 LAST $SEC 1
J 0
(825 225);
DISPLAY 0.680851 (825 225);
PAINT MONO (825 225);
DISPLAY INVISIBLE (825 225);
FORCEPROP 0 LAST CDS_SEC 1
J 0
(825 225);
DISPLAY 0.680851 (825 225);
DISPLAY INVISIBLE (825 225);
FORCEPROP 1 LASTPIN (725 200) $PN 1
J 2
(713 212);
DISPLAY 0.787234 (713 212);
PAINT MONO (713 212);
FORCEPROP 1 LASTPIN (525 200) $PN 2
J 2
(563 212);
DISPLAY 0.787234 (563 212);
PAINT MONO (563 212);
FORCEPROP 1 LAST MATERIAL EMPTY
J 0
(450 175);
DISPLAY 0.489362 (450 175);
PAINT RED (450 175);
FORCEPROP 1 LAST VALUE 0
J 0
(475 200);
DISPLAY 0.489362 (475 200);
PAINT SKYBLUE (475 200);
FORCEPROP 2 LAST CDS_LIB pure_quanta
J 0
(625 200);
DISPLAY INVISIBLE (625 200);
FORCEPROP 1 LAST PACK_TYPE 0402LF
J 0
(450 125);
DISPLAY 0.489362 (450 125);
PAINT SKYBLUE (450 125);
DISPLAY INVISIBLE (450 125);
FORCEPROP 1 LAST TOLERANCE 5%
J 2
(750 175);
DISPLAY 0.489362 (750 175);
PAINT SKYBLUE (750 175);
DISPLAY INVISIBLE (750 175);
FORCEPROP 1 LAST WATTAGE 1/16W
J 0
(700 125);
DISPLAY 0.489362 (700 125);
PAINT SKYBLUE (700 125);
DISPLAY INVISIBLE (700 125);
FORCEPROP 2 LAST BOM_COST MEM
J 0
(600 350);
DISPLAY 0.744681 (600 350);
PAINT WHITE (600 350);
DISPLAY INVISIBLE (600 350);
FORCEPROP 1 LAST PATH I41
J 2
(675 350);
DISPLAY 0.978723 (675 350);
PAINT WHITE (675 350);
DISPLAY INVISIBLE (675 350);
FORCEPROP 1 LAST PART_NUMBER CS00002JB13
J 0
(525 250);
DISPLAY 0.489362 (525 250);
PAINT SKYBLUE (525 250);
DISPLAY INVISIBLE (525 250);
FORCEADD Q_RES..1
(1625 -500);
FORCEPROP 1 LAST LOCATION R1175
J 0
(1425 -500);
DISPLAY 0.723404 (1425 -500);
FORCEPROP 0 LAST $SEC 1
J 0
(1875 -450);
DISPLAY 0.680851 (1875 -450);
PAINT MONO (1875 -450);
DISPLAY INVISIBLE (1875 -450);
FORCEPROP 0 LAST CDS_SEC 1
J 0
(1875 -450);
DISPLAY 0.680851 (1875 -450);
DISPLAY INVISIBLE (1875 -450);
FORCEPROP 1 LASTPIN (1525 -500) $PN 1
J 0
(1537 -488);
DISPLAY 0.787234 (1537 -488);
PAINT MONO (1537 -488);
FORCEPROP 1 LASTPIN (1725 -500) $PN 2
J 0
(1687 -488);
DISPLAY 0.787234 (1687 -488);
PAINT MONO (1687 -488);
FORCEPROP 1 LAST VALUE 33.2
J 2
(1875 -500);
DISPLAY 0.723404 (1875 -500);
FORCEPROP 1 LAST PACK_TYPE 0402LF
J 0
(1450 -550);
DISPLAY 0.723404 (1450 -550);
FORCEPROP 1 LAST MATERIAL CHIP
J 0
(1700 -550);
DISPLAY 0.723404 (1700 -550);
FORCEPROP 2 LAST CDS_LIB pure_quanta
J 0
(1625 -500);
DISPLAY INVISIBLE (1625 -500);
FORCEPROP 1 LAST TOLERANCE 1%
J 0
(2100 -500);
DISPLAY 0.723404 (2100 -500);
PAINT SKYBLUE (2100 -500);
DISPLAY INVISIBLE (2100 -500);
FORCEPROP 1 LAST WATTAGE 1/16W
J 2
(2025 -550);
DISPLAY 0.723404 (2025 -550);
PAINT SKYBLUE (2025 -550);
DISPLAY INVISIBLE (2025 -550);
FORCEPROP 1 LAST PATH I42
J 0
(1575 -350);
DISPLAY 0.978723 (1575 -350);
PAINT WHITE (1575 -350);
DISPLAY INVISIBLE (1575 -350);
FORCEPROP 1 LAST PART_NUMBER CS03322FB03
J 0
(1225 -600);
DISPLAY 0.723404 (1225 -600);
PAINT WHITE (1225 -600);
DISPLAY INVISIBLE (1225 -600);
FORCEADD UNIVERSAL_GND..1
(-50 350);
FORCEPROP 3 LASTPIN (-50 400) SIG_NAME GND\g
J 0
(-40 410);
DISPLAY 0.659574 (-40 410);
PAINT MONO (-40 410);
DISPLAY INVISIBLE (-40 410);
FORCEPROP 2 LAST CDS_LIB pure_quanta_power
J 0
(-50 350);
DISPLAY INVISIBLE (-50 350);
FORCEPROP 1 LAST HDL_POWER GND
J 1
(-25 275);
DISPLAY 0.872340 (-25 275);
PAINT GREEN (-25 275);
DISPLAY INVISIBLE (-25 275);
FORCEPROP 1 LAST PATH I43
J 0
(25 350);
DISPLAY 0.872340 (25 350);
PAINT AQUA (25 350);
DISPLAY INVISIBLE (25 350);
FORCEADD UNIVERSAL_GND..1
(125 2150);
FORCEPROP 3 LASTPIN (125 2200) SIG_NAME GND\g
J 0
(135 2210);
DISPLAY 0.659574 (135 2210);
PAINT MONO (135 2210);
DISPLAY INVISIBLE (135 2210);
FORCEPROP 2 LAST CDS_LIB pure_quanta_power
J 0
(125 2150);
DISPLAY INVISIBLE (125 2150);
FORCEPROP 1 LAST HDL_POWER GND
J 1
(150 2075);
DISPLAY 0.872340 (150 2075);
PAINT GREEN (150 2075);
DISPLAY INVISIBLE (150 2075);
FORCEPROP 1 LAST PATH I44
J 0
(200 2150);
DISPLAY 0.872340 (200 2150);
PAINT AQUA (200 2150);
DISPLAY INVISIBLE (200 2150);
FORCEADD SN74LVC1G07DBVR..1
(700 2350);
FORCEPROP 1 LAST LOCATION U34
J 0
(575 2605);
DISPLAY 0.723404 (575 2605);
PAINT GREEN (575 2605);
FORCEPROP 0 LAST $SEC 1
J 0
(575 2750);
DISPLAY 0.680851 (575 2750);
PAINT MONO (575 2750);
DISPLAY INVISIBLE (575 2750);
FORCEPROP 0 LAST CDS_SEC 1
J 0
(575 2750);
DISPLAY 0.680851 (575 2750);
DISPLAY INVISIBLE (575 2750);
FORCEPROP 0 LASTPIN (525 2350) $PN 2
J 2
(515 2360);
DISPLAY 0.680851 (515 2360);
PAINT MONO (515 2360);
FORCEPROP 0 LASTPIN (525 2250) $PN 3
J 2
(515 2260);
DISPLAY 0.680851 (515 2260);
PAINT MONO (515 2260);
FORCEPROP 0 LASTPIN (875 2250) $PN 1
J 0
(885 2260);
DISPLAY 0.680851 (885 2260);
PAINT MONO (885 2260);
FORCEPROP 0 LASTPIN (525 2450) $PN 5
J 2
(515 2460);
DISPLAY 0.680851 (515 2460);
PAINT MONO (515 2460);
FORCEPROP 0 LASTPIN (875 2350) $PN 4
J 0
(885 2360);
DISPLAY 0.680851 (885 2360);
PAINT MONO (885 2360);
FORCEPROP 1 LAST MATERIAL IC
J 0
(575 2510);
DISPLAY 0.723404 (575 2510);
PAINT GREEN (575 2510);
FORCEPROP 2 LAST VALUE SN74LVC1G07DBVR
J 0
(575 2700);
DISPLAY 0.680851 (575 2700);
FORCEPROP 2 LAST PACK_TYPE SMLF
J 0
(575 2650);
DISPLAY 0.680851 (575 2650);
FORCEPROP 1 LAST NEEDS_NO_SIZE TRUE
J 0
(700 2350);
DISPLAY 0.468085 (700 2350);
PAINT GREEN (700 2350);
DISPLAY INVISIBLE (700 2350);
FORCEPROP 2 LAST CDS_LIB pure_quanta
J 0
(700 2350);
DISPLAY INVISIBLE (700 2350);
FORCEPROP 1 LAST PATH I45
J 0
(800 2505);
DISPLAY 0.723404 (800 2505);
PAINT GREEN (800 2505);
DISPLAY INVISIBLE (800 2505);
FORCEPROP 1 LAST PART_NUMBER AL1G0007024
J 0
(575 2560);
DISPLAY 0.723404 (575 2560);
PAINT GREEN (575 2560);
DISPLAY INVISIBLE (575 2560);
FORCEADD Q_CAP..1
(850 1000);
FORCEPROP 1 LAST LOCATION C1064
J 0
(900 1100);
DISPLAY 0.787234 (900 1100);
FORCEPROP 0 LAST $SEC 1
J 0
(900 1150);
DISPLAY 0.680851 (900 1150);
PAINT MONO (900 1150);
DISPLAY INVISIBLE (900 1150);
FORCEPROP 0 LAST CDS_SEC 1
J 0
(900 1150);
DISPLAY 0.680851 (900 1150);
DISPLAY INVISIBLE (900 1150);
FORCEPROP 1 LASTPIN (850 1100) $PN 1
J 0
(860 1080);
DISPLAY 0.787234 (860 1080);
PAINT MONO (860 1080);
FORCEPROP 1 LASTPIN (850 900) $PN 2
J 0
(860 880);
DISPLAY 0.787234 (860 880);
PAINT MONO (860 880);
FORCEPROP 1 LAST VOLTAGE 25V
J 0
(900 1000);
DISPLAY 0.787234 (900 1000);
FORCEPROP 1 LAST VALUE 0.1UF
J 0
(900 1050);
DISPLAY 0.787234 (900 1050);
FORCEPROP 1 LAST TOLERANCE 10%
J 0
(900 950);
DISPLAY 0.787234 (900 950);
FORCEPROP 1 LAST MATERIAL X7R
J 0
(900 900);
DISPLAY 0.787234 (900 900);
PAINT RED (900 900);
FORCEPROP 1 LAST PACK_TYPE 0402
J 0
(900 800);
DISPLAY 0.787234 (900 800);
FORCEPROP 2 LAST CDS_LIB pure_quanta
J 0
(850 1000);
DISPLAY INVISIBLE (850 1000);
FORCEPROP 1 LAST PATH I46
J 0
(900 1150);
DISPLAY 0.978723 (900 1150);
PAINT WHITE (900 1150);
DISPLAY INVISIBLE (900 1150);
FORCEPROP 1 LAST PART_NUMBER CH4104K1B00
J 0
(900 850);
DISPLAY 0.787234 (900 850);
DISPLAY INVISIBLE (900 850);
FORCEADD UNIVERSAL_GND..1
(850 800);
FORCEPROP 3 LASTPIN (850 850) SIG_NAME GND\g
J 0
(860 860);
DISPLAY 0.659574 (860 860);
PAINT MONO (860 860);
DISPLAY INVISIBLE (860 860);
FORCEPROP 2 LAST CDS_LIB pure_quanta_power
J 0
(850 800);
DISPLAY INVISIBLE (850 800);
FORCEPROP 1 LAST HDL_POWER GND
J 1
(875 725);
DISPLAY 0.872340 (875 725);
PAINT GREEN (875 725);
DISPLAY INVISIBLE (875 725);
FORCEPROP 1 LAST PATH I47
J 0
(925 800);
DISPLAY 0.872340 (925 800);
PAINT AQUA (925 800);
DISPLAY INVISIBLE (925 800);
FORCEADD UNIVERSAL_POWER..1
R 2
(850 1275);
FORCEPROP 3 LASTPIN (850 1225) SIG_NAME P3V3_AUX\g
J 0
(860 1235);
DISPLAY 0.659574 (860 1235);
PAINT MONO (860 1235);
DISPLAY INVISIBLE (860 1235);
FORCEPROP 1 LAST HDL_POWER P3V3_AUX
J 1
(850 1325);
DISPLAY 0.723404 (850 1325);
PAINT GREEN (850 1325);
FORCEPROP 2 LAST CDS_LIB pure_quanta_power
J 0
(850 1275);
DISPLAY INVISIBLE (850 1275);
FORCEPROP 1 LAST PATH I48
J 2
(800 1300);
DISPLAY 0.872340 (800 1300);
PAINT AQUA (800 1300);
DISPLAY INVISIBLE (800 1300);
FORCEADD Q_RES..1
(1850 675);
FORCEPROP 1 LAST LOCATION R1177
J 0
(1650 675);
DISPLAY 0.723404 (1650 675);
FORCEPROP 0 LAST $SEC 1
J 0
(2100 725);
DISPLAY 0.680851 (2100 725);
PAINT MONO (2100 725);
DISPLAY INVISIBLE (2100 725);
FORCEPROP 0 LAST CDS_SEC 1
J 0
(2100 725);
DISPLAY 0.680851 (2100 725);
DISPLAY INVISIBLE (2100 725);
FORCEPROP 1 LASTPIN (1750 675) $PN 1
J 0
(1762 687);
DISPLAY 0.787234 (1762 687);
PAINT MONO (1762 687);
FORCEPROP 1 LASTPIN (1950 675) $PN 2
J 0
(1912 687);
DISPLAY 0.787234 (1912 687);
PAINT MONO (1912 687);
FORCEPROP 1 LAST MATERIAL CHIP
J 0
(1925 625);
DISPLAY 0.723404 (1925 625);
FORCEPROP 1 LAST VALUE 33.2
J 2
(2100 675);
DISPLAY 0.723404 (2100 675);
FORCEPROP 1 LAST PACK_TYPE 0402LF
J 0
(1675 625);
DISPLAY 0.723404 (1675 625);
FORCEPROP 1 LAST WATTAGE 1/16W
J 2
(2250 625);
DISPLAY 0.723404 (2250 625);
PAINT SKYBLUE (2250 625);
DISPLAY INVISIBLE (2250 625);
FORCEPROP 1 LAST TOLERANCE 1%
J 0
(2325 675);
DISPLAY 0.723404 (2325 675);
PAINT SKYBLUE (2325 675);
DISPLAY INVISIBLE (2325 675);
FORCEPROP 2 LAST CDS_LIB pure_quanta
J 0
(1850 675);
DISPLAY INVISIBLE (1850 675);
FORCEPROP 1 LAST PATH I49
J 0
(1800 825);
DISPLAY 0.978723 (1800 825);
PAINT WHITE (1800 825);
DISPLAY INVISIBLE (1800 825);
FORCEPROP 1 LAST PART_NUMBER CS03322FB03
J 0
(1450 575);
DISPLAY 0.723404 (1450 575);
PAINT WHITE (1450 575);
DISPLAY INVISIBLE (1450 575);
FORCEADD Q_CAP..1
R 2
(-3300 2000);
FORCEPROP 1 LAST LOCATION C1061
J 2
(-3350 2150);
DISPLAY 0.978723 (-3350 2150);
FORCEPROP 0 LAST $SEC 1
J 0
(-3350 2200);
DISPLAY 0.680851 (-3350 2200);
PAINT MONO (-3350 2200);
DISPLAY INVISIBLE (-3350 2200);
FORCEPROP 0 LAST CDS_SEC 1
J 0
(-3350 2200);
DISPLAY 0.680851 (-3350 2200);
DISPLAY INVISIBLE (-3350 2200);
FORCEPROP 1 LASTPIN (-3300 2100) $PN 1
J 2
(-3310 2080);
DISPLAY 0.787234 (-3310 2080);
PAINT MONO (-3310 2080);
FORCEPROP 1 LASTPIN (-3300 1900) $PN 2
J 2
(-3310 1880);
DISPLAY 0.787234 (-3310 1880);
PAINT MONO (-3310 1880);
FORCEPROP 1 LAST TOLERANCE 10%
J 2
(-3350 2000);
DISPLAY 0.787234 (-3350 2000);
FORCEPROP 1 LAST VOLTAGE 25V
J 2
(-3350 2050);
DISPLAY 0.787234 (-3350 2050);
FORCEPROP 1 LAST MATERIAL X7R
J 2
(-3350 1950);
DISPLAY 0.787234 (-3350 1950);
PAINT RED (-3350 1950);
FORCEPROP 1 LAST PACK_TYPE 0402
J 2
(-3350 1850);
DISPLAY 0.787234 (-3350 1850);
FORCEPROP 1 LAST VALUE 0.1UF
J 2
(-3350 2100);
DISPLAY 0.787234 (-3350 2100);
FORCEPROP 2 LAST CDS_LIB pure_quanta
J 2
(-3300 2000);
DISPLAY INVISIBLE (-3300 2000);
FORCEPROP 1 LAST PATH I5
J 2
(-3350 2150);
DISPLAY 0.978723 (-3350 2150);
PAINT WHITE (-3350 2150);
DISPLAY INVISIBLE (-3350 2150);
FORCEPROP 1 LAST PART_NUMBER CH4104K1B00
J 2
(-3350 1900);
DISPLAY 0.787234 (-3350 1900);
DISPLAY INVISIBLE (-3350 1900);
FORCEADD OFFPAGE..2
(2600 -500);
PAINT AQUA (2600 -500);
FORCEPROP 2 LAST $XR2 139 
J 0
(3029 -500);
DISPLAY 0.638298 (3029 -500);
PAINT MONO (3029 -500);
FORCEPROP 2 LAST $XR1 138 
J 0
(2909 -500);
DISPLAY 0.638298 (2909 -500);
PAINT MONO (2909 -500);
FORCEPROP 2 LAST $XR0 137 
J 0
(2789 -500);
DISPLAY 0.638298 (2789 -500);
PAINT MONO (2789 -500);
FORCEPROP 2 LAST CDS_LIB standard
J 0
(2600 -500);
DISPLAY INVISIBLE (2600 -500);
FORCEPROP 1 LAST OFFPAGE TRUE
J 0
(2925 -625);
DISPLAY 0.872340 (2925 -625);
PAINT AQUA (2925 -625);
DISPLAY INVISIBLE (2925 -625);
FORCEPROP 1 LAST COMMENT_BODY TRUE
J 0
(2555 -595);
DISPLAY 0.872340 (2555 -595);
PAINT GREEN (2555 -595);
DISPLAY INVISIBLE (2555 -595);
FORCEPROP 2 LAST PATH I50
J 0
(2925 -450);
DISPLAY 0.680851 (2925 -450);
DISPLAY INVISIBLE (2925 -450);
FORCEADD Q_RES..2
(2500 -25);
FORCEPROP 1 LAST LOCATION R1172
J 0
(2545 100);
DISPLAY 0.978723 (2545 100);
FORCEPROP 0 LAST $SEC 1
J 0
(2550 150);
DISPLAY 0.680851 (2550 150);
PAINT MONO (2550 150);
DISPLAY INVISIBLE (2550 150);
FORCEPROP 0 LAST CDS_SEC 1
J 0
(2550 150);
DISPLAY 0.680851 (2550 150);
DISPLAY INVISIBLE (2550 150);
FORCEPROP 1 LASTPIN (2500 75) $PN 1
J 0
(2505 37);
DISPLAY 0.787234 (2505 37);
PAINT MONO (2505 37);
FORCEPROP 1 LASTPIN (2500 -125) $PN 2
J 0
(2505 -115);
DISPLAY 0.787234 (2505 -115);
PAINT MONO (2505 -115);
FORCEPROP 1 LAST PACK_TYPE 0402LF
J 0
(2540 -200);
DISPLAY 0.978723 (2540 -200);
FORCEPROP 1 LAST VALUE 10K
J 0
(2545 50);
DISPLAY 0.978723 (2545 50);
FORCEPROP 1 LAST MATERIAL EMPTY
J 0
(2540 -100);
DISPLAY 0.978723 (2540 -100);
PAINT RED (2540 -100);
FORCEPROP 1 LAST WATTAGE 1/16W
J 0
(2540 -50);
DISPLAY 0.978723 (2540 -50);
FORCEPROP 1 LAST TOLERANCE 5%
J 0
(2545 0);
DISPLAY 0.978723 (2545 0);
FORCEPROP 2 LAST CDS_LIB pure_quanta
J 0
(2500 -25);
DISPLAY INVISIBLE (2500 -25);
FORCEPROP 1 LAST PATH I51
J 0
(2550 150);
DISPLAY 0.978723 (2550 150);
PAINT WHITE (2550 150);
DISPLAY INVISIBLE (2550 150);
FORCEPROP 1 LAST PART_NUMBER CS31002JB08
J 0
(2540 -150);
DISPLAY 0.978723 (2540 -150);
DISPLAY INVISIBLE (2540 -150);
FORCEADD UNIVERSAL_POWER..1
R 2
(2500 225);
FORCEPROP 3 LASTPIN (2500 175) SIG_NAME P3V3_AUX\g
J 0
(2510 185);
DISPLAY 0.659574 (2510 185);
PAINT MONO (2510 185);
DISPLAY INVISIBLE (2510 185);
FORCEPROP 1 LAST HDL_POWER P3V3_AUX
J 1
(2500 275);
DISPLAY 0.723404 (2500 275);
PAINT GREEN (2500 275);
FORCEPROP 2 LAST CDS_LIB pure_quanta_power
J 0
(2500 225);
DISPLAY INVISIBLE (2500 225);
FORCEPROP 1 LAST PATH I52
J 2
(2450 250);
DISPLAY 0.872340 (2450 250);
PAINT AQUA (2450 250);
DISPLAY INVISIBLE (2450 250);
FORCEADD OFFPAGE..2
(2950 675);
PAINT AQUA (2950 675);
FORCEPROP 2 LAST $XR0 139 
J 0
(3139 675);
DISPLAY 0.638298 (3139 675);
PAINT MONO (3139 675);
FORCEPROP 2 LAST CDS_LIB standard
J 0
(2950 675);
DISPLAY INVISIBLE (2950 675);
FORCEPROP 1 LAST OFFPAGE TRUE
J 0
(3275 550);
DISPLAY 0.872340 (3275 550);
PAINT AQUA (3275 550);
DISPLAY INVISIBLE (3275 550);
FORCEPROP 1 LAST COMMENT_BODY TRUE
J 0
(2905 580);
DISPLAY 0.872340 (2905 580);
PAINT GREEN (2905 580);
DISPLAY INVISIBLE (2905 580);
FORCEPROP 2 LAST PATH I53
J 0
(3150 725);
DISPLAY 0.680851 (3150 725);
DISPLAY INVISIBLE (3150 725);
FORCEADD UNIVERSAL_GND..1
(-25 2550);
FORCEPROP 3 LASTPIN (-25 2600) SIG_NAME GND\g
J 0
(-15 2610);
DISPLAY 0.659574 (-15 2610);
PAINT MONO (-15 2610);
DISPLAY INVISIBLE (-15 2610);
FORCEPROP 2 LAST CDS_LIB pure_quanta_power
J 0
(-25 2550);
DISPLAY INVISIBLE (-25 2550);
FORCEPROP 1 LAST HDL_POWER GND
J 1
(0 2475);
DISPLAY 0.872340 (0 2475);
PAINT GREEN (0 2475);
DISPLAY INVISIBLE (0 2475);
FORCEPROP 1 LAST PATH I54
J 0
(50 2550);
DISPLAY 0.872340 (50 2550);
PAINT AQUA (50 2550);
DISPLAY INVISIBLE (50 2550);
FORCEADD Q_CAP..1
R 2
(-25 2775);
FORCEPROP 1 LAST LOCATION C1063
J 2
(-75 2925);
DISPLAY 0.978723 (-75 2925);
FORCEPROP 0 LAST $SEC 1
J 0
(-75 2975);
DISPLAY 0.680851 (-75 2975);
PAINT MONO (-75 2975);
DISPLAY INVISIBLE (-75 2975);
FORCEPROP 0 LAST CDS_SEC 1
J 0
(-75 2975);
DISPLAY 0.680851 (-75 2975);
DISPLAY INVISIBLE (-75 2975);
FORCEPROP 1 LASTPIN (-25 2875) $PN 1
J 2
(-35 2855);
DISPLAY 0.787234 (-35 2855);
PAINT MONO (-35 2855);
FORCEPROP 1 LASTPIN (-25 2675) $PN 2
J 2
(-35 2655);
DISPLAY 0.787234 (-35 2655);
PAINT MONO (-35 2655);
FORCEPROP 1 LAST MATERIAL X7R
J 2
(-75 2725);
DISPLAY 0.787234 (-75 2725);
PAINT RED (-75 2725);
FORCEPROP 1 LAST TOLERANCE 10%
J 2
(-75 2775);
DISPLAY 0.787234 (-75 2775);
FORCEPROP 1 LAST PACK_TYPE 0402
J 2
(-75 2625);
DISPLAY 0.787234 (-75 2625);
FORCEPROP 1 LAST VOLTAGE 25V
J 2
(-75 2825);
DISPLAY 0.787234 (-75 2825);
FORCEPROP 1 LAST VALUE 0.1UF
J 2
(-75 2875);
DISPLAY 0.787234 (-75 2875);
FORCEPROP 2 LAST CDS_LIB pure_quanta
J 0
(-25 2775);
DISPLAY INVISIBLE (-25 2775);
FORCEPROP 1 LAST PATH I55
J 2
(-75 2925);
DISPLAY 0.978723 (-75 2925);
PAINT WHITE (-75 2925);
DISPLAY INVISIBLE (-75 2925);
FORCEPROP 1 LAST PART_NUMBER CH4104K1B00
J 2
(-75 2675);
DISPLAY 0.787234 (-75 2675);
DISPLAY INVISIBLE (-75 2675);
FORCEADD UNIVERSAL_POWER..1
R 2
(0 3100);
FORCEPROP 3 LASTPIN (0 3050) SIG_NAME P3V3_AUX\g
J 0
(10 3060);
DISPLAY 0.659574 (10 3060);
PAINT MONO (10 3060);
DISPLAY INVISIBLE (10 3060);
FORCEPROP 1 LAST HDL_POWER P3V3_AUX
J 1
(0 3150);
DISPLAY 0.723404 (0 3150);
PAINT GREEN (0 3150);
FORCEPROP 2 LAST CDS_LIB pure_quanta_power
J 0
(0 3100);
DISPLAY INVISIBLE (0 3100);
FORCEPROP 1 LAST PATH I56
J 2
(-50 3125);
DISPLAY 0.872340 (-50 3125);
PAINT AQUA (-50 3125);
DISPLAY INVISIBLE (-50 3125);
FORCEADD Q_RES..1
(450 3275);
FORCEPROP 1 LAST LOCATION R1168
J 0
(400 3325);
DISPLAY 0.978723 (400 3325);
FORCEPROP 0 LAST $SEC 1
J 0
(400 3375);
DISPLAY 0.680851 (400 3375);
PAINT MONO (400 3375);
DISPLAY INVISIBLE (400 3375);
FORCEPROP 0 LAST CDS_SEC 1
J 0
(400 3375);
DISPLAY 0.680851 (400 3375);
DISPLAY INVISIBLE (400 3375);
FORCEPROP 1 LASTPIN (350 3275) $PN 1
J 0
(362 3287);
DISPLAY 0.787234 (362 3287);
PAINT MONO (362 3287);
FORCEPROP 1 LASTPIN (550 3275) $PN 2
J 0
(512 3287);
DISPLAY 0.787234 (512 3287);
PAINT MONO (512 3287);
FORCEPROP 1 LAST VALUE 0
J 2
(600 3275);
DISPLAY 0.510638 (600 3275);
FORCEPROP 1 LAST MATERIAL CHIP
J 0
(375 3200);
DISPLAY 0.510638 (375 3200);
PAINT RED (375 3200);
FORCEPROP 1 LAST TOLERANCE 5%
J 0
(625 3275);
DISPLAY 0.510638 (625 3275);
FORCEPROP 1 LAST WATTAGE 1/16W
J 2
(650 3200);
DISPLAY 0.510638 (650 3200);
FORCEPROP 1 LAST PACK_TYPE 0402LF
J 0
(700 3275);
DISPLAY 0.510638 (700 3275);
FORCEPROP 2 LAST CDS_LIB pure_quanta
J 0
(450 3275);
DISPLAY INVISIBLE (450 3275);
FORCEPROP 1 LAST PATH I57
J 0
(400 3425);
DISPLAY 0.978723 (400 3425);
PAINT WHITE (400 3425);
DISPLAY INVISIBLE (400 3425);
FORCEPROP 1 LAST PART_NUMBER CS00002JB13
J 0
(375 3225);
DISPLAY 0.510638 (375 3225);
DISPLAY INVISIBLE (375 3225);
FORCEADD Q_RES..1
(1775 2350);
FORCEPROP 1 LAST LOCATION R1170
J 0
(1725 2400);
DISPLAY 0.978723 (1725 2400);
FORCEPROP 0 LAST $SEC 1
J 0
(1725 2450);
DISPLAY 0.680851 (1725 2450);
PAINT MONO (1725 2450);
DISPLAY INVISIBLE (1725 2450);
FORCEPROP 0 LAST CDS_SEC 1
J 0
(1725 2450);
DISPLAY 0.680851 (1725 2450);
DISPLAY INVISIBLE (1725 2450);
FORCEPROP 1 LASTPIN (1675 2350) $PN 1
J 0
(1687 2362);
DISPLAY 0.787234 (1687 2362);
PAINT MONO (1687 2362);
FORCEPROP 1 LASTPIN (1875 2350) $PN 2
J 0
(1837 2362);
DISPLAY 0.787234 (1837 2362);
PAINT MONO (1837 2362);
FORCEPROP 1 LAST MATERIAL CHIP
J 0
(1700 2275);
DISPLAY 0.510638 (1700 2275);
PAINT RED (1700 2275);
FORCEPROP 1 LAST VALUE 0
J 2
(1925 2350);
DISPLAY 0.510638 (1925 2350);
FORCEPROP 1 LAST WATTAGE 1/16W
J 2
(1975 2275);
DISPLAY 0.510638 (1975 2275);
FORCEPROP 1 LAST TOLERANCE 5%
J 0
(1950 2350);
DISPLAY 0.510638 (1950 2350);
FORCEPROP 1 LAST PACK_TYPE 0402LF
J 0
(2025 2350);
DISPLAY 0.510638 (2025 2350);
FORCEPROP 2 LAST CDS_LIB pure_quanta
J 0
(1775 2350);
DISPLAY INVISIBLE (1775 2350);
FORCEPROP 1 LAST PATH I58
J 0
(1725 2500);
DISPLAY 0.978723 (1725 2500);
PAINT WHITE (1725 2500);
DISPLAY INVISIBLE (1725 2500);
FORCEPROP 1 LAST PART_NUMBER CS00002JB13
J 0
(1700 2300);
DISPLAY 0.510638 (1700 2300);
DISPLAY INVISIBLE (1700 2300);
FORCEADD OFFPAGE..2
(1650 3275);
PAINT AQUA (1650 3275);
FORCEPROP 2 LAST $XR2 248 
J 0
(2079 3275);
DISPLAY 0.638298 (2079 3275);
PAINT MONO (2079 3275);
FORCEPROP 2 LAST $XR1 141 
J 0
(1959 3275);
DISPLAY 0.638298 (1959 3275);
PAINT MONO (1959 3275);
FORCEPROP 2 LAST $XR0 140 
J 0
(1839 3275);
DISPLAY 0.638298 (1839 3275);
PAINT MONO (1839 3275);
FORCEPROP 2 LAST CDS_LIB standard
J 0
(1650 3275);
DISPLAY INVISIBLE (1650 3275);
FORCEPROP 1 LAST OFFPAGE TRUE
J 0
(1975 3150);
DISPLAY 0.872340 (1975 3150);
PAINT AQUA (1975 3150);
DISPLAY INVISIBLE (1975 3150);
FORCEPROP 1 LAST COMMENT_BODY TRUE
J 0
(1605 3180);
DISPLAY 0.872340 (1605 3180);
PAINT GREEN (1605 3180);
DISPLAY INVISIBLE (1605 3180);
FORCEPROP 2 LAST PATH I59
J 0
(1825 3350);
DISPLAY 0.680851 (1825 3350);
DISPLAY INVISIBLE (1825 3350);
FORCEADD UNIVERSAL_POWER..1
R 2
(-3275 2325);
FORCEPROP 3 LASTPIN (-3275 2275) SIG_NAME P3V3_AUX\g
J 0
(-3265 2285);
DISPLAY 0.659574 (-3265 2285);
PAINT MONO (-3265 2285);
DISPLAY INVISIBLE (-3265 2285);
FORCEPROP 1 LAST HDL_POWER P3V3_AUX
J 1
(-3275 2375);
DISPLAY 0.723404 (-3275 2375);
PAINT GREEN (-3275 2375);
FORCEPROP 2 LAST CDS_LIB pure_quanta_power
J 0
(-3275 2325);
DISPLAY INVISIBLE (-3275 2325);
FORCEPROP 1 LAST PATH I6
J 2
(-3325 2350);
DISPLAY 0.872340 (-3325 2350);
PAINT AQUA (-3325 2350);
DISPLAY INVISIBLE (-3325 2350);
FORCEADD Q_RES..2
R 2
(2275 2700);
FORCEPROP 1 LAST LOCATION R1171
J 2
(2230 2825);
DISPLAY 0.638298 (2230 2825);
FORCEPROP 0 LAST $SEC 1
J 0
(2250 2875);
DISPLAY 0.680851 (2250 2875);
PAINT MONO (2250 2875);
DISPLAY INVISIBLE (2250 2875);
FORCEPROP 0 LAST CDS_SEC 1
J 0
(2250 2875);
DISPLAY 0.680851 (2250 2875);
DISPLAY INVISIBLE (2250 2875);
FORCEPROP 1 LASTPIN (2275 2800) $PN 1
J 2
(2270 2762);
DISPLAY 0.787234 (2270 2762);
PAINT MONO (2270 2762);
FORCEPROP 1 LASTPIN (2275 2600) $PN 2
J 2
(2270 2610);
DISPLAY 0.787234 (2270 2610);
PAINT MONO (2270 2610);
FORCEPROP 1 LAST PACK_TYPE 0402LF
J 2
(2235 2525);
DISPLAY 0.638298 (2235 2525);
FORCEPROP 1 LAST VALUE 1K
J 2
(2230 2775);
DISPLAY 0.638298 (2230 2775);
FORCEPROP 1 LAST TOLERANCE 1%
J 2
(2230 2725);
DISPLAY 0.638298 (2230 2725);
FORCEPROP 1 LAST MATERIAL CHIP
J 2
(2235 2625);
DISPLAY 0.638298 (2235 2625);
FORCEPROP 1 LAST WATTAGE 1/16W
J 2
(2235 2675);
DISPLAY 0.638298 (2235 2675);
FORCEPROP 2 LAST CDS_LIB pure_quanta
J 0
(2275 2700);
DISPLAY INVISIBLE (2275 2700);
FORCEPROP 1 LAST PATH I60
J 2
(2225 2875);
DISPLAY 0.978723 (2225 2875);
PAINT WHITE (2225 2875);
DISPLAY INVISIBLE (2225 2875);
FORCEPROP 1 LAST PART_NUMBER CS21002FB06
J 2
(2235 2575);
DISPLAY 0.638298 (2235 2575);
DISPLAY INVISIBLE (2235 2575);
FORCEADD UNIVERSAL_POWER..1
R 2
(2275 2950);
FORCEPROP 3 LASTPIN (2275 2900) SIG_NAME P3V3_AUX\g
J 0
(2285 2910);
DISPLAY 0.659574 (2285 2910);
PAINT MONO (2285 2910);
DISPLAY INVISIBLE (2285 2910);
FORCEPROP 1 LAST HDL_POWER P3V3_AUX
J 1
(2275 3000);
DISPLAY 0.723404 (2275 3000);
PAINT GREEN (2275 3000);
FORCEPROP 2 LAST CDS_LIB pure_quanta_power
J 0
(2275 2950);
DISPLAY INVISIBLE (2275 2950);
FORCEPROP 1 LAST PATH I61
J 2
(2225 2975);
DISPLAY 0.872340 (2225 2975);
PAINT AQUA (2225 2975);
DISPLAY INVISIBLE (2225 2975);
FORCEADD OFFPAGE..2
(3200 2350);
PAINT AQUA (3200 2350);
FORCEPROP 2 LAST $XR0 80 
J 0
(3389 2350);
DISPLAY 0.638298 (3389 2350);
PAINT MONO (3389 2350);
FORCEPROP 2 LAST CDS_LIB standard
J 0
(3200 2350);
DISPLAY INVISIBLE (3200 2350);
FORCEPROP 1 LAST OFFPAGE TRUE
J 0
(3525 2225);
DISPLAY 0.872340 (3525 2225);
PAINT AQUA (3525 2225);
DISPLAY INVISIBLE (3525 2225);
FORCEPROP 1 LAST COMMENT_BODY TRUE
J 0
(3155 2255);
DISPLAY 0.872340 (3155 2255);
PAINT GREEN (3155 2255);
DISPLAY INVISIBLE (3155 2255);
FORCEPROP 2 LAST PATH I62
J 0
(3375 2425);
DISPLAY 0.680851 (3375 2425);
DISPLAY INVISIBLE (3375 2425);
FORCEADD 74LVC1G08W57..1
(300 725);
FORCEPROP 1 LAST LOCATION U35
J 0
(156 1156);
DISPLAY 0.723404 (156 1156);
PAINT GREEN (156 1156);
FORCEPROP 0 LAST $SEC 1
J 0
(175 1200);
DISPLAY 0.680851 (175 1200);
PAINT MONO (175 1200);
DISPLAY INVISIBLE (175 1200);
FORCEPROP 0 LAST CDS_SEC 1
J 0
(175 1200);
DISPLAY 0.680851 (175 1200);
DISPLAY INVISIBLE (175 1200);
FORCEPROP 0 LASTPIN (0 825) $PN 1
J 2
(-10 835);
DISPLAY 0.680851 (-10 835);
PAINT MONO (-10 835);
FORCEPROP 0 LASTPIN (0 725) $PN 2
J 2
(-10 735);
DISPLAY 0.680851 (-10 735);
PAINT MONO (-10 735);
FORCEPROP 0 LASTPIN (0 625) $PN 3
J 2
(-10 635);
DISPLAY 0.680851 (-10 635);
PAINT MONO (-10 635);
FORCEPROP 0 LASTPIN (600 825) $PN 5
J 0
(610 835);
DISPLAY 0.680851 (610 835);
PAINT MONO (610 835);
FORCEPROP 0 LASTPIN (600 675) $PN 4
J 0
(610 685);
DISPLAY 0.680851 (610 685);
PAINT MONO (610 685);
FORCEPROP 2 LAST VALUE 74LVC1G08W5-7
J 0
(150 1000);
DISPLAY 0.808511 (150 1000);
FORCEPROP 1 LAST MATERIAL IC
J 0
(156 882);
DISPLAY 0.723404 (156 882);
PAINT GREEN (156 882);
FORCEPROP 2 LAST PART_TYPE SMLF
J 0
(150 1050);
DISPLAY 0.808511 (150 1050);
FORCEPROP 1 LAST NEEDS_NO_SIZE TRUE
J 0
(300 725);
DISPLAY 0.723404 (300 725);
PAINT GREEN (300 725);
DISPLAY INVISIBLE (300 725);
FORCEPROP 1 LAST CDS_LMAN_SYM_OUTLINE -150,150,150,-150
J 0
(300 725);
DISPLAY 0.468085 (300 725);
PAINT GREEN (300 725);
DISPLAY INVISIBLE (300 725);
FORCEPROP 2 LAST CDS_LIB pure_quanta
J 0
(300 725);
DISPLAY INVISIBLE (300 725);
FORCEPROP 1 LAST PATH I63
J 0
(300 725);
DISPLAY 0.723404 (300 725);
PAINT GREEN (300 725);
DISPLAY INVISIBLE (300 725);
FORCEPROP 1 LAST PART_NUMBER AL1G0008020
J 0
(150 950);
DISPLAY 0.723404 (150 950);
PAINT GREEN (150 950);
DISPLAY INVISIBLE (150 950);
FORCEADD SN74LVC1G07DBVR..1
(-2575 1575);
FORCEPROP 1 LAST LOCATION U33
J 0
(-2700 1830);
DISPLAY 0.723404 (-2700 1830);
PAINT GREEN (-2700 1830);
FORCEPROP 0 LAST $SEC 1
J 0
(-2700 1975);
DISPLAY 0.680851 (-2700 1975);
PAINT MONO (-2700 1975);
DISPLAY INVISIBLE (-2700 1975);
FORCEPROP 0 LAST CDS_SEC 1
J 0
(-2700 1975);
DISPLAY 0.680851 (-2700 1975);
DISPLAY INVISIBLE (-2700 1975);
FORCEPROP 0 LASTPIN (-2750 1575) $PN 2
J 2
(-2760 1585);
DISPLAY 0.680851 (-2760 1585);
PAINT MONO (-2760 1585);
FORCEPROP 0 LASTPIN (-2750 1475) $PN 3
J 2
(-2760 1485);
DISPLAY 0.680851 (-2760 1485);
PAINT MONO (-2760 1485);
FORCEPROP 0 LASTPIN (-2400 1475) $PN 1
J 0
(-2390 1485);
DISPLAY 0.680851 (-2390 1485);
PAINT MONO (-2390 1485);
FORCEPROP 0 LASTPIN (-2750 1675) $PN 5
J 2
(-2760 1685);
DISPLAY 0.680851 (-2760 1685);
PAINT MONO (-2760 1685);
FORCEPROP 0 LASTPIN (-2400 1575) $PN 4
J 0
(-2390 1585);
DISPLAY 0.680851 (-2390 1585);
PAINT MONO (-2390 1585);
FORCEPROP 2 LAST VALUE SN74LVC1G07DBVR
J 0
(-2700 1925);
DISPLAY 0.680851 (-2700 1925);
FORCEPROP 1 LAST MATERIAL IC
J 0
(-2700 1735);
DISPLAY 0.723404 (-2700 1735);
PAINT GREEN (-2700 1735);
FORCEPROP 2 LAST PACK_TYPE SMLF
J 0
(-2700 1875);
DISPLAY 0.680851 (-2700 1875);
FORCEPROP 1 LAST NEEDS_NO_SIZE TRUE
J 0
(-2575 1575);
DISPLAY 0.468085 (-2575 1575);
PAINT GREEN (-2575 1575);
DISPLAY INVISIBLE (-2575 1575);
FORCEPROP 2 LAST CDS_LIB pure_quanta
J 0
(-2575 1575);
DISPLAY INVISIBLE (-2575 1575);
FORCEPROP 1 LAST PATH I64
J 0
(-2475 1730);
DISPLAY 0.723404 (-2475 1730);
PAINT GREEN (-2475 1730);
DISPLAY INVISIBLE (-2475 1730);
FORCEPROP 1 LAST PART_NUMBER AL1G0007024
J 0
(-2700 1785);
DISPLAY 0.723404 (-2700 1785);
PAINT GREEN (-2700 1785);
DISPLAY INVISIBLE (-2700 1785);
FORCEADD UNIVERSAL_GND..1
(-5150 -1675);
FORCEPROP 3 LASTPIN (-5150 -1625) SIG_NAME GND\g
J 0
(-5140 -1615);
DISPLAY 0.659574 (-5140 -1615);
PAINT MONO (-5140 -1615);
DISPLAY INVISIBLE (-5140 -1615);
FORCEPROP 2 LAST CDS_LIB pure_quanta_power
J 0
(-5150 -1675);
DISPLAY INVISIBLE (-5150 -1675);
FORCEPROP 1 LAST HDL_POWER GND
J 1
(-5125 -1750);
DISPLAY 0.872340 (-5125 -1750);
PAINT GREEN (-5125 -1750);
DISPLAY INVISIBLE (-5125 -1750);
FORCEPROP 1 LAST PATH I65
J 0
(-5075 -1675);
DISPLAY 0.872340 (-5075 -1675);
PAINT AQUA (-5075 -1675);
DISPLAY INVISIBLE (-5075 -1675);
FORCEADD Q_CAP..1
R 2
(-5150 -1400);
FORCEPROP 1 LAST LOCATION C8009
J 2
(-5200 -1300);
DISPLAY 0.787234 (-5200 -1300);
FORCEPROP 0 LAST $SEC 1
J 0
(-5200 -1250);
DISPLAY 0.680851 (-5200 -1250);
PAINT MONO (-5200 -1250);
DISPLAY INVISIBLE (-5200 -1250);
FORCEPROP 0 LAST CDS_SEC 1
J 0
(-5200 -1250);
DISPLAY 0.680851 (-5200 -1250);
DISPLAY INVISIBLE (-5200 -1250);
FORCEPROP 1 LASTPIN (-5150 -1300) $PN 1
J 2
(-5160 -1320);
DISPLAY 0.787234 (-5160 -1320);
PAINT MONO (-5160 -1320);
FORCEPROP 1 LASTPIN (-5150 -1500) $PN 2
J 2
(-5160 -1520);
DISPLAY 0.787234 (-5160 -1520);
PAINT MONO (-5160 -1520);
FORCEPROP 1 LAST PACK_TYPE 0402
J 2
(-5200 -1600);
DISPLAY 0.787234 (-5200 -1600);
FORCEPROP 1 LAST TOLERANCE 10%
J 2
(-5200 -1450);
DISPLAY 0.787234 (-5200 -1450);
FORCEPROP 1 LAST MATERIAL X7R
J 2
(-5200 -1500);
DISPLAY 0.787234 (-5200 -1500);
PAINT RED (-5200 -1500);
FORCEPROP 1 LAST VOLTAGE 25V
J 2
(-5200 -1400);
DISPLAY 0.787234 (-5200 -1400);
FORCEPROP 1 LAST VALUE 0.1UF
J 2
(-5200 -1350);
DISPLAY 0.787234 (-5200 -1350);
FORCEPROP 2 LAST CDS_LIB pure_quanta
J 0
(-5150 -1400);
DISPLAY INVISIBLE (-5150 -1400);
FORCEPROP 1 LAST PATH I66
J 2
(-5200 -1250);
DISPLAY 0.978723 (-5200 -1250);
PAINT WHITE (-5200 -1250);
DISPLAY INVISIBLE (-5200 -1250);
FORCEPROP 1 LAST PART_NUMBER CH4104K1B00
J 2
(-5200 -1550);
DISPLAY 0.787234 (-5200 -1550);
DISPLAY INVISIBLE (-5200 -1550);
FORCEADD APX80929SAG7..1
R 2
(-4600 -1150);
FORCEPROP 1 LAST LOCATION U8002
J 2
(-4375 -831);
DISPLAY 0.723404 (-4375 -831);
PAINT GREEN (-4375 -831);
FORCEPROP 2 LAST SEC 1
J 0
(-4375 -675);
DISPLAY 0.680851 (-4375 -675);
PAINT MONO (-4375 -675);
DISPLAY INVISIBLE (-4375 -675);
FORCEPROP 2 LASTPIN (-4225 -1050) $PN 1
J 0
(-4215 -1040);
DISPLAY 0.680851 (-4215 -1040);
PAINT MONO (-4215 -1040);
FORCEPROP 2 LASTPIN (-4225 -1250) $PN 2
J 0
(-4215 -1240);
DISPLAY 0.680851 (-4215 -1240);
PAINT MONO (-4215 -1240);
FORCEPROP 2 LASTPIN (-4975 -1150) $PN 3
J 2
(-4985 -1140);
DISPLAY 0.680851 (-4985 -1140);
PAINT MONO (-4985 -1140);
FORCEPROP 2 LAST VALUE APX809-29SAG-7
J 2
(-4375 -775);
DISPLAY 0.680851 (-4375 -775);
FORCEPROP 2 LAST PART_TYPE SMLF
J 2
(-4375 -725);
DISPLAY 0.680851 (-4375 -725);
FORCEPROP 1 LAST MATERIAL IC
J 2
(-4375 -940);
DISPLAY 0.723404 (-4375 -940);
PAINT GREEN (-4375 -940);
FORCEPROP 2 LAST SEC_TYPE 
J 0
(-4375 -675);
DISPLAY 0.680851 (-4375 -675);
DISPLAY INVISIBLE (-4375 -675);
FORCEPROP 2 LAST CDS_LIB pure_quanta
J 0
(-4600 -1150);
DISPLAY INVISIBLE (-4600 -1150);
FORCEPROP 1 LAST CDS_LMAN_SYM_OUTLINE -225,200,225,-200
J 2
(-4600 -1150);
DISPLAY 0.468085 (-4600 -1150);
PAINT GREEN (-4600 -1150);
DISPLAY INVISIBLE (-4600 -1150);
FORCEPROP 1 LAST NEEDS_NO_SIZE TRUE
J 2
(-4825 -1310);
DISPLAY 0.723404 (-4825 -1310);
PAINT GREEN (-4825 -1310);
DISPLAY INVISIBLE (-4825 -1310);
FORCEPROP 1 LAST PATH I67
J 2
(-4825 -1350);
DISPLAY 0.723404 (-4825 -1350);
PAINT GREEN (-4825 -1350);
DISPLAY INVISIBLE (-4825 -1350);
FORCEPROP 1 LAST PART_NUMBER AL080929000
J 2
(-4375 -883);
DISPLAY 0.723404 (-4375 -883);
PAINT GREEN (-4375 -883);
DISPLAY INVISIBLE (-4375 -883);
FORCEADD UNIVERSAL_POWER..1
R 2
(-5150 -875);
FORCEPROP 3 LASTPIN (-5150 -925) SIG_NAME P3V3_OCP_V3_2_R\g
J 0
(-5140 -915);
DISPLAY 0.659574 (-5140 -915);
PAINT MONO (-5140 -915);
DISPLAY INVISIBLE (-5140 -915);
FORCEPROP 1 LAST HDL_POWER P3V3_OCP_V3_2_R
J 1
(-5150 -825);
DISPLAY 0.723404 (-5150 -825);
PAINT GREEN (-5150 -825);
FORCEPROP 2 LAST CDS_LIB pure_quanta_power
J 0
(-5150 -875);
DISPLAY INVISIBLE (-5150 -875);
FORCEPROP 1 LAST PATH I68
J 2
(-5200 -850);
DISPLAY 0.872340 (-5200 -850);
PAINT AQUA (-5200 -850);
DISPLAY INVISIBLE (-5200 -850);
FORCEADD UNIVERSAL_GND..1
(-3525 -1775);
FORCEPROP 3 LASTPIN (-3525 -1725) SIG_NAME GND\g
J 0
(-3515 -1715);
DISPLAY 0.659574 (-3515 -1715);
PAINT MONO (-3515 -1715);
DISPLAY INVISIBLE (-3515 -1715);
FORCEPROP 2 LAST CDS_LIB pure_quanta_power
J 0
(-3525 -1775);
DISPLAY INVISIBLE (-3525 -1775);
FORCEPROP 1 LAST HDL_POWER GND
J 1
(-3500 -1850);
DISPLAY 0.872340 (-3500 -1850);
PAINT GREEN (-3500 -1850);
DISPLAY INVISIBLE (-3500 -1850);
FORCEPROP 1 LAST PATH I69
J 0
(-3450 -1775);
DISPLAY 0.872340 (-3450 -1775);
PAINT AQUA (-3450 -1775);
DISPLAY INVISIBLE (-3450 -1775);
FORCEADD OFFPAGE..1
(-3200 725);
PAINT AQUA (-3200 725);
FORCEPROP 2 LAST $XR1 142 
J 0
(-3572 725);
DISPLAY 0.638298 (-3572 725);
PAINT MONO (-3572 725);
FORCEPROP 2 LAST $XR0 140 
J 0
(-3452 725);
DISPLAY 0.638298 (-3452 725);
PAINT MONO (-3452 725);
FORCEPROP 2 LAST CDS_LIB standard
J 0
(-3200 725);
DISPLAY INVISIBLE (-3200 725);
FORCEPROP 1 LAST OFFPAGE TRUE
J 0
(-2875 600);
DISPLAY 0.872340 (-2875 600);
PAINT AQUA (-2875 600);
DISPLAY INVISIBLE (-2875 600);
FORCEPROP 1 LAST COMMENT_BODY TRUE
J 0
(-3075 625);
DISPLAY 0.872340 (-3075 625);
PAINT GREEN (-3075 625);
DISPLAY INVISIBLE (-3075 625);
FORCEPROP 2 LAST PATH I7
J 0
(-3150 800);
DISPLAY 0.680851 (-3150 800);
DISPLAY INVISIBLE (-3150 800);
FORCEADD Q_RES..2
(-3525 -1525);
FORCEPROP 1 LAST LOCATION R8096
J 0
(-3480 -1400);
DISPLAY 0.978723 (-3480 -1400);
FORCEPROP 0 LAST $SEC 1
J 0
(-3475 -1350);
DISPLAY 0.680851 (-3475 -1350);
PAINT MONO (-3475 -1350);
DISPLAY INVISIBLE (-3475 -1350);
FORCEPROP 0 LAST CDS_SEC 1
J 0
(-3475 -1350);
DISPLAY 0.680851 (-3475 -1350);
DISPLAY INVISIBLE (-3475 -1350);
FORCEPROP 1 LASTPIN (-3525 -1425) $PN 1
J 0
(-3520 -1463);
DISPLAY 0.787234 (-3520 -1463);
PAINT MONO (-3520 -1463);
FORCEPROP 1 LASTPIN (-3525 -1625) $PN 2
J 0
(-3520 -1615);
DISPLAY 0.787234 (-3520 -1615);
PAINT MONO (-3520 -1615);
FORCEPROP 1 LAST PACK_TYPE 0402LF
J 0
(-3485 -1700);
DISPLAY 0.978723 (-3485 -1700);
FORCEPROP 1 LAST MATERIAL CHIP
J 0
(-3485 -1600);
DISPLAY 0.978723 (-3485 -1600);
PAINT RED (-3485 -1600);
FORCEPROP 1 LAST WATTAGE 1/16W
J 0
(-3485 -1550);
DISPLAY 0.978723 (-3485 -1550);
FORCEPROP 1 LAST VALUE 100K
J 0
(-3480 -1450);
DISPLAY 0.978723 (-3480 -1450);
FORCEPROP 1 LAST TOLERANCE 1%
J 0
(-3480 -1500);
DISPLAY 0.978723 (-3480 -1500);
FORCEPROP 2 LAST CDS_LIB pure_quanta
J 0
(-3525 -1525);
DISPLAY INVISIBLE (-3525 -1525);
FORCEPROP 1 LAST PATH I70
J 0
(-3475 -1350);
DISPLAY 0.978723 (-3475 -1350);
PAINT WHITE (-3475 -1350);
DISPLAY INVISIBLE (-3475 -1350);
FORCEPROP 1 LAST PART_NUMBER CS41002FB09
J 0
(-3485 -1650);
DISPLAY 0.978723 (-3485 -1650);
DISPLAY INVISIBLE (-3485 -1650);
FORCEADD UNIVERSAL_GND..1
(-4050 -1150);
FORCEPROP 3 LASTPIN (-4050 -1100) SIG_NAME GND\g
J 0
(-4040 -1090);
DISPLAY 0.659574 (-4040 -1090);
PAINT MONO (-4040 -1090);
DISPLAY INVISIBLE (-4040 -1090);
FORCEPROP 2 LAST CDS_LIB pure_quanta_power
J 0
(-4050 -1150);
DISPLAY INVISIBLE (-4050 -1150);
FORCEPROP 1 LAST HDL_POWER GND
J 1
(-4025 -1225);
DISPLAY 0.872340 (-4025 -1225);
PAINT GREEN (-4025 -1225);
DISPLAY INVISIBLE (-4025 -1225);
FORCEPROP 1 LAST PATH I71
J 0
(-3975 -1150);
DISPLAY 0.872340 (-3975 -1150);
PAINT AQUA (-3975 -1150);
DISPLAY INVISIBLE (-3975 -1150);
FORCEADD UNIVERSAL_POWER..1
R 2
(-3375 -725);
FORCEPROP 3 LASTPIN (-3375 -775) SIG_NAME P3V3_OCP_V3_2_R\g
J 0
(-3365 -765);
DISPLAY 0.659574 (-3365 -765);
PAINT MONO (-3365 -765);
DISPLAY INVISIBLE (-3365 -765);
FORCEPROP 1 LAST HDL_POWER P3V3_OCP_V3_2_R
J 1
(-3375 -675);
DISPLAY 0.723404 (-3375 -675);
PAINT GREEN (-3375 -675);
FORCEPROP 2 LAST CDS_LIB pure_quanta_power
J 0
(-3375 -725);
DISPLAY INVISIBLE (-3375 -725);
FORCEPROP 1 LAST PATH I72
J 2
(-3425 -700);
DISPLAY 0.872340 (-3425 -700);
PAINT AQUA (-3425 -700);
DISPLAY INVISIBLE (-3425 -700);
FORCEADD Q_RES..1
(-3050 -1250);
FORCEPROP 1 LAST LOCATION R8097
J 0
(-3275 -1250);
DISPLAY 0.787234 (-3275 -1250);
FORCEPROP 0 LAST $SEC 1
J 0
(-3275 -1200);
DISPLAY 0.680851 (-3275 -1200);
PAINT MONO (-3275 -1200);
DISPLAY INVISIBLE (-3275 -1200);
FORCEPROP 0 LAST CDS_SEC 1
J 0
(-3275 -1200);
DISPLAY 0.680851 (-3275 -1200);
DISPLAY INVISIBLE (-3275 -1200);
FORCEPROP 1 LASTPIN (-3150 -1250) $PN 1
J 0
(-3138 -1238);
DISPLAY 0.787234 (-3138 -1238);
PAINT MONO (-3138 -1238);
FORCEPROP 1 LASTPIN (-2950 -1250) $PN 2
J 0
(-2988 -1238);
DISPLAY 0.787234 (-2988 -1238);
PAINT MONO (-2988 -1238);
FORCEPROP 1 LAST WATTAGE 1/16W
J 2
(-2875 -1325);
DISPLAY 0.510638 (-2875 -1325);
FORCEPROP 1 LAST PACK_TYPE 0402LF
J 0
(-2800 -1250);
DISPLAY 0.510638 (-2800 -1250);
FORCEPROP 1 LAST VALUE 0
J 2
(-2900 -1250);
DISPLAY 0.510638 (-2900 -1250);
FORCEPROP 1 LAST TOLERANCE 5%
J 0
(-2875 -1250);
DISPLAY 0.510638 (-2875 -1250);
FORCEPROP 1 LAST MATERIAL CHIP
J 0
(-3125 -1325);
DISPLAY 0.510638 (-3125 -1325);
PAINT RED (-3125 -1325);
FORCEPROP 2 LAST CDS_LIB pure_quanta
J 0
(-3050 -1250);
DISPLAY INVISIBLE (-3050 -1250);
FORCEPROP 1 LAST PATH I73
J 0
(-3100 -1100);
DISPLAY 0.978723 (-3100 -1100);
PAINT WHITE (-3100 -1100);
DISPLAY INVISIBLE (-3100 -1100);
FORCEPROP 1 LAST PART_NUMBER CS00002JB13
J 0
(-3125 -1300);
DISPLAY 0.510638 (-3125 -1300);
DISPLAY INVISIBLE (-3125 -1300);
FORCEADD OFFPAGE..2
(-1700 -1250);
PAINT AQUA (-1700 -1250);
FORCEPROP 2 LAST $XR1 142 
J 0
(-1391 -1250);
DISPLAY 0.638298 (-1391 -1250);
PAINT MONO (-1391 -1250);
FORCEPROP 2 LAST $XR0 140 
J 0
(-1511 -1250);
DISPLAY 0.638298 (-1511 -1250);
PAINT MONO (-1511 -1250);
FORCEPROP 2 LAST CDS_LIB standard
J 0
(-1700 -1250);
DISPLAY INVISIBLE (-1700 -1250);
FORCEPROP 1 LAST OFFPAGE TRUE
J 0
(-1375 -1375);
DISPLAY 0.872340 (-1375 -1375);
PAINT AQUA (-1375 -1375);
DISPLAY INVISIBLE (-1375 -1375);
FORCEPROP 1 LAST COMMENT_BODY TRUE
J 0
(-1745 -1345);
DISPLAY 0.872340 (-1745 -1345);
PAINT GREEN (-1745 -1345);
DISPLAY INVISIBLE (-1745 -1345);
FORCEPROP 2 LAST PATH I74
J 0
(-1375 -1200);
DISPLAY 0.680851 (-1375 -1200);
DISPLAY INVISIBLE (-1375 -1200);
FORCEADD Q_RES..2
R 2
(-3375 -950);
FORCEPROP 1 LAST LOCATION R8095
J 2
(-3420 -825);
DISPLAY 0.787234 (-3420 -825);
FORCEPROP 0 LAST $SEC 1
J 2
(-3425 -775);
DISPLAY 0.680851 (-3425 -775);
PAINT MONO (-3425 -775);
DISPLAY INVISIBLE (-3425 -775);
FORCEPROP 0 LAST CDS_SEC 1
J 2
(-3425 -775);
DISPLAY 0.680851 (-3425 -775);
DISPLAY INVISIBLE (-3425 -775);
FORCEPROP 1 LASTPIN (-3375 -850) $PN 1
J 2
(-3380 -888);
DISPLAY 0.787234 (-3380 -888);
PAINT MONO (-3380 -888);
FORCEPROP 1 LASTPIN (-3375 -1050) $PN 2
J 2
(-3380 -1040);
DISPLAY 0.787234 (-3380 -1040);
PAINT MONO (-3380 -1040);
FORCEPROP 1 LAST WATTAGE 1/16W
J 2
(-3415 -975);
DISPLAY 0.787234 (-3415 -975);
FORCEPROP 1 LAST VALUE 10K
J 2
(-3420 -875);
DISPLAY 0.787234 (-3420 -875);
FORCEPROP 1 LAST TOLERANCE 5%
J 2
(-3420 -925);
DISPLAY 0.787234 (-3420 -925);
FORCEPROP 1 LAST PACK_TYPE 0402LF
J 2
(-3415 -1125);
DISPLAY 0.787234 (-3415 -1125);
FORCEPROP 1 LAST MATERIAL EMPTY
J 2
(-3415 -1025);
DISPLAY 0.787234 (-3415 -1025);
PAINT RED (-3415 -1025);
FORCEPROP 2 LAST CDS_LIB pure_quanta
J 2
(-3375 -950);
DISPLAY INVISIBLE (-3375 -950);
FORCEPROP 1 LAST PATH I77
J 2
(-3425 -775);
DISPLAY 0.978723 (-3425 -775);
PAINT WHITE (-3425 -775);
DISPLAY INVISIBLE (-3425 -775);
FORCEPROP 1 LAST PART_NUMBER CS31002JB08
J 2
(-3415 -1075);
DISPLAY 0.787234 (-3415 -1075);
DISPLAY INVISIBLE (-3415 -1075);
FORCEADD 74LVC1G08W57..1
(-4275 625);
FORCEPROP 1 LAST LOCATION U9051
J 0
(-4494 1081);
DISPLAY 0.723404 (-4494 1081);
PAINT GREEN (-4494 1081);
FORCEPROP 0 LAST $SEC 1
J 0
(-4475 1125);
DISPLAY 0.680851 (-4475 1125);
PAINT MONO (-4475 1125);
DISPLAY INVISIBLE (-4475 1125);
FORCEPROP 0 LAST CDS_SEC 1
J 0
(-4475 1125);
DISPLAY 0.680851 (-4475 1125);
DISPLAY INVISIBLE (-4475 1125);
FORCEPROP 0 LASTPIN (-4575 725) $PN 1
J 2
(-4585 735);
DISPLAY 0.680851 (-4585 735);
PAINT MONO (-4585 735);
FORCEPROP 0 LASTPIN (-4575 625) $PN 2
J 2
(-4585 635);
DISPLAY 0.680851 (-4585 635);
PAINT MONO (-4585 635);
FORCEPROP 0 LASTPIN (-4575 525) $PN 3
J 2
(-4585 535);
DISPLAY 0.680851 (-4585 535);
PAINT MONO (-4585 535);
FORCEPROP 0 LASTPIN (-3975 725) $PN 5
J 0
(-3965 735);
DISPLAY 0.680851 (-3965 735);
PAINT MONO (-3965 735);
FORCEPROP 0 LASTPIN (-3975 575) $PN 4
J 0
(-3965 585);
DISPLAY 0.680851 (-3965 585);
PAINT MONO (-3965 585);
FORCEPROP 2 LAST VALUE 74LVC1G08W5-7
J 0
(-4500 925);
DISPLAY 0.808511 (-4500 925);
FORCEPROP 1 LAST MATERIAL IC
J 0
(-4494 807);
DISPLAY 0.723404 (-4494 807);
PAINT GREEN (-4494 807);
FORCEPROP 2 LAST PART_TYPE SMLF
J 0
(-4500 975);
DISPLAY 0.808511 (-4500 975);
FORCEPROP 2 LAST CDS_LIB pure_quanta
J 0
(-4275 625);
DISPLAY INVISIBLE (-4275 625);
FORCEPROP 1 LAST CDS_LMAN_SYM_OUTLINE -150,150,150,-150
J 0
(-4275 625);
DISPLAY 0.468085 (-4275 625);
PAINT GREEN (-4275 625);
DISPLAY INVISIBLE (-4275 625);
FORCEPROP 1 LAST NEEDS_NO_SIZE TRUE
J 0
(-4275 625);
DISPLAY 0.723404 (-4275 625);
PAINT GREEN (-4275 625);
DISPLAY INVISIBLE (-4275 625);
FORCEPROP 1 LAST PATH I78
J 0
(-4275 625);
DISPLAY 0.723404 (-4275 625);
PAINT GREEN (-4275 625);
DISPLAY INVISIBLE (-4275 625);
FORCEPROP 1 LAST PART_NUMBER AL1G0008020
J 0
(-4500 875);
DISPLAY 0.723404 (-4500 875);
PAINT GREEN (-4500 875);
DISPLAY INVISIBLE (-4500 875);
FORCEADD UNIVERSAL_GND..1
(-4625 275);
FORCEPROP 3 LASTPIN (-4625 325) SIG_NAME GND\g
J 0
(-4615 335);
DISPLAY 0.659574 (-4615 335);
PAINT MONO (-4615 335);
DISPLAY INVISIBLE (-4615 335);
FORCEPROP 2 LAST CDS_LIB pure_quanta_power
J 0
(-4625 275);
DISPLAY INVISIBLE (-4625 275);
FORCEPROP 1 LAST HDL_POWER GND
J 1
(-4600 200);
DISPLAY 0.872340 (-4600 200);
PAINT GREEN (-4600 200);
DISPLAY INVISIBLE (-4600 200);
FORCEPROP 1 LAST PATH I79
J 0
(-4550 275);
DISPLAY 0.872340 (-4550 275);
PAINT AQUA (-4550 275);
DISPLAY INVISIBLE (-4550 275);
FORCEADD OFFPAGE..1
(-2150 825);
PAINT AQUA (-2150 825);
FORCEPROP 2 LAST $XR0 81 
J 0
(-2401 825);
DISPLAY 0.638298 (-2401 825);
PAINT MONO (-2401 825);
FORCEPROP 2 LAST CDS_LIB standard
J 0
(-2150 825);
DISPLAY INVISIBLE (-2150 825);
FORCEPROP 1 LAST OFFPAGE TRUE
J 0
(-1825 700);
DISPLAY 0.872340 (-1825 700);
PAINT AQUA (-1825 700);
DISPLAY INVISIBLE (-1825 700);
FORCEPROP 1 LAST COMMENT_BODY TRUE
J 0
(-2025 725);
DISPLAY 0.872340 (-2025 725);
PAINT GREEN (-2025 725);
DISPLAY INVISIBLE (-2025 725);
FORCEPROP 2 LAST PATH I8
J 0
(-2350 875);
DISPLAY 0.680851 (-2350 875);
DISPLAY INVISIBLE (-2350 875);
FORCEADD UNIVERSAL_POWER..1
R 2
(-3850 1275);
FORCEPROP 3 LASTPIN (-3850 1225) SIG_NAME P3V3_AUX\g
J 0
(-3840 1235);
DISPLAY 0.659574 (-3840 1235);
PAINT MONO (-3840 1235);
DISPLAY INVISIBLE (-3840 1235);
FORCEPROP 1 LAST HDL_POWER P3V3_AUX
J 1
(-3850 1325);
DISPLAY 0.723404 (-3850 1325);
PAINT GREEN (-3850 1325);
FORCEPROP 2 LAST CDS_LIB pure_quanta_power
J 0
(-3850 1275);
DISPLAY INVISIBLE (-3850 1275);
FORCEPROP 1 LAST PATH I80
J 2
(-3900 1300);
DISPLAY 0.872340 (-3900 1300);
PAINT AQUA (-3900 1300);
DISPLAY INVISIBLE (-3900 1300);
FORCEADD Q_CAP..1
(-3850 975);
FORCEPROP 1 LAST LOCATION C9051
J 0
(-3800 1075);
DISPLAY 0.787234 (-3800 1075);
FORCEPROP 0 LAST $SEC 1
J 0
(-3800 1125);
DISPLAY 0.680851 (-3800 1125);
PAINT MONO (-3800 1125);
DISPLAY INVISIBLE (-3800 1125);
FORCEPROP 0 LAST CDS_SEC 1
J 0
(-3800 1125);
DISPLAY 0.680851 (-3800 1125);
DISPLAY INVISIBLE (-3800 1125);
FORCEPROP 1 LASTPIN (-3850 1075) $PN 1
J 0
(-3840 1055);
DISPLAY 0.787234 (-3840 1055);
PAINT MONO (-3840 1055);
FORCEPROP 1 LASTPIN (-3850 875) $PN 2
J 0
(-3840 855);
DISPLAY 0.787234 (-3840 855);
PAINT MONO (-3840 855);
FORCEPROP 1 LAST MATERIAL X7R
J 0
(-3800 875);
DISPLAY 0.787234 (-3800 875);
PAINT RED (-3800 875);
FORCEPROP 1 LAST VOLTAGE 25V
J 0
(-3800 975);
DISPLAY 0.787234 (-3800 975);
FORCEPROP 1 LAST TOLERANCE 10%
J 0
(-3800 925);
DISPLAY 0.787234 (-3800 925);
FORCEPROP 1 LAST PACK_TYPE 0402
J 0
(-3800 775);
DISPLAY 0.787234 (-3800 775);
FORCEPROP 1 LAST VALUE 0.1UF
J 0
(-3800 1025);
DISPLAY 0.787234 (-3800 1025);
FORCEPROP 2 LAST CDS_LIB pure_quanta
J 0
(-3850 975);
DISPLAY INVISIBLE (-3850 975);
FORCEPROP 1 LAST PATH I81
J 0
(-3800 1125);
DISPLAY 0.978723 (-3800 1125);
PAINT WHITE (-3800 1125);
DISPLAY INVISIBLE (-3800 1125);
FORCEPROP 1 LAST PART_NUMBER CH4104K1B00
J 0
(-3800 825);
DISPLAY 0.787234 (-3800 825);
DISPLAY INVISIBLE (-3800 825);
FORCEADD UNIVERSAL_GND..1
(-3850 750);
FORCEPROP 3 LASTPIN (-3850 800) SIG_NAME GND\g
J 0
(-3840 810);
DISPLAY 0.659574 (-3840 810);
PAINT MONO (-3840 810);
DISPLAY INVISIBLE (-3840 810);
FORCEPROP 2 LAST CDS_LIB pure_quanta_power
J 0
(-3850 750);
DISPLAY INVISIBLE (-3850 750);
FORCEPROP 1 LAST HDL_POWER GND
J 1
(-3825 675);
DISPLAY 0.872340 (-3825 675);
PAINT GREEN (-3825 675);
DISPLAY INVISIBLE (-3825 675);
FORCEPROP 1 LAST PATH I82
J 0
(-3775 750);
DISPLAY 0.872340 (-3775 750);
PAINT AQUA (-3775 750);
DISPLAY INVISIBLE (-3775 750);
FORCEADD OFFPAGE..1
(-5425 75);
PAINT AQUA (-5425 75);
FORCEPROP 2 LAST $XR3 248 
J 0
(-5677 3);
DISPLAY 0.638298 (-5677 3);
PAINT MONO (-5677 3);
FORCEPROP 2 LAST $XR2 142 
J 0
(-5677 111);
DISPLAY 0.638298 (-5677 111);
PAINT MONO (-5677 111);
FORCEPROP 2 LAST $XR1 141 
J 0
(-5677 39);
DISPLAY 0.638298 (-5677 39);
PAINT MONO (-5677 39);
FORCEPROP 2 LAST $XR0 140 
J 0
(-5677 75);
DISPLAY 0.638298 (-5677 75);
PAINT MONO (-5677 75);
FORCEPROP 2 LAST CDS_LIB standard
J 0
(-5425 75);
DISPLAY INVISIBLE (-5425 75);
FORCEPROP 1 LAST OFFPAGE TRUE
J 0
(-5100 -50);
DISPLAY 0.872340 (-5100 -50);
PAINT AQUA (-5100 -50);
DISPLAY INVISIBLE (-5100 -50);
FORCEPROP 1 LAST COMMENT_BODY TRUE
J 0
(-5300 -25);
DISPLAY 0.872340 (-5300 -25);
PAINT GREEN (-5300 -25);
DISPLAY INVISIBLE (-5300 -25);
FORCEPROP 2 LAST PATH I83
J 0
(-5375 150);
DISPLAY 0.680851 (-5375 150);
DISPLAY INVISIBLE (-5375 150);
FORCEADD Q_RES..1
(-4325 75);
FORCEPROP 1 LAST LOCATION R1523
J 0
(-4375 125);
DISPLAY 0.978723 (-4375 125);
PAINT SKYBLUE (-4375 125);
FORCEPROP 0 LAST $SEC 1
J 0
(-4375 175);
DISPLAY 0.680851 (-4375 175);
PAINT MONO (-4375 175);
DISPLAY INVISIBLE (-4375 175);
FORCEPROP 0 LAST CDS_SEC 1
J 0
(-4375 175);
DISPLAY 0.680851 (-4375 175);
DISPLAY INVISIBLE (-4375 175);
FORCEPROP 1 LASTPIN (-4425 75) $PN 1
J 0
(-4413 87);
DISPLAY 0.787234 (-4413 87);
PAINT MONO (-4413 87);
FORCEPROP 1 LASTPIN (-4225 75) $PN 2
J 0
(-4263 87);
DISPLAY 0.787234 (-4263 87);
PAINT MONO (-4263 87);
FORCEPROP 1 LAST WATTAGE 1/16W
J 2
(-4125 0);
DISPLAY 0.510638 (-4125 0);
FORCEPROP 1 LAST PACK_TYPE 0402LF
J 0
(-4075 75);
DISPLAY 0.510638 (-4075 75);
FORCEPROP 1 LAST VALUE 0
J 2
(-4175 75);
DISPLAY 0.510638 (-4175 75);
FORCEPROP 1 LAST TOLERANCE 5%
J 0
(-4150 75);
DISPLAY 0.510638 (-4150 75);
FORCEPROP 1 LAST MATERIAL CHIP
J 0
(-4400 0);
DISPLAY 0.510638 (-4400 0);
PAINT RED (-4400 0);
FORCEPROP 2 LAST CDS_LIB pure_quanta
J 0
(-4325 75);
DISPLAY INVISIBLE (-4325 75);
FORCEPROP 1 LAST PATH I84
J 0
(-4375 225);
DISPLAY 0.978723 (-4375 225);
PAINT WHITE (-4375 225);
DISPLAY INVISIBLE (-4375 225);
FORCEPROP 1 LAST PART_NUMBER CS00002JB13
J 0
(-4400 25);
DISPLAY 0.510638 (-4400 25);
DISPLAY INVISIBLE (-4400 25);
FORCEADD OFFPAGE..2
(-2750 75);
PAINT AQUA (-2750 75);
FORCEPROP 2 LAST $XR0 142 
J 0
(-2561 75);
DISPLAY 0.638298 (-2561 75);
PAINT MONO (-2561 75);
FORCEPROP 2 LAST CDS_LIB standard
J 0
(-2750 75);
DISPLAY INVISIBLE (-2750 75);
FORCEPROP 1 LAST OFFPAGE TRUE
J 0
(-2425 -50);
DISPLAY 0.872340 (-2425 -50);
PAINT AQUA (-2425 -50);
DISPLAY INVISIBLE (-2425 -50);
FORCEPROP 1 LAST COMMENT_BODY TRUE
J 0
(-2795 -20);
DISPLAY 0.872340 (-2795 -20);
PAINT GREEN (-2795 -20);
DISPLAY INVISIBLE (-2795 -20);
FORCEPROP 2 LAST PATH I85
J 0
(-2575 150);
DISPLAY 0.680851 (-2575 150);
DISPLAY INVISIBLE (-2575 150);
FORCEADD OFFPAGE..1
(-5350 625);
PAINT AQUA (-5350 625);
FORCEPROP 2 LAST $XR0 142 
J 0
(-5602 625);
DISPLAY 0.638298 (-5602 625);
PAINT MONO (-5602 625);
FORCEPROP 2 LAST CDS_LIB standard
J 0
(-5350 625);
DISPLAY INVISIBLE (-5350 625);
FORCEPROP 1 LAST OFFPAGE TRUE
J 0
(-5025 500);
DISPLAY 0.872340 (-5025 500);
PAINT AQUA (-5025 500);
DISPLAY INVISIBLE (-5025 500);
FORCEPROP 1 LAST COMMENT_BODY TRUE
J 0
(-5225 525);
DISPLAY 0.872340 (-5225 525);
PAINT GREEN (-5225 525);
DISPLAY INVISIBLE (-5225 525);
FORCEPROP 2 LAST PATH I86
J 0
(-5300 700);
DISPLAY 0.680851 (-5300 700);
DISPLAY INVISIBLE (-5300 700);
FORCEADD OFFPAGE..1
(-5350 725);
PAINT AQUA (-5350 725);
FORCEPROP 2 LAST $XR1 142 
J 0
(-5602 689);
DISPLAY 0.638298 (-5602 689);
PAINT MONO (-5602 689);
FORCEPROP 2 LAST $XR0 140 
J 0
(-5602 725);
DISPLAY 0.638298 (-5602 725);
PAINT MONO (-5602 725);
FORCEPROP 2 LAST CDS_LIB standard
J 0
(-5350 725);
DISPLAY INVISIBLE (-5350 725);
FORCEPROP 1 LAST OFFPAGE TRUE
J 0
(-5025 600);
DISPLAY 0.872340 (-5025 600);
PAINT AQUA (-5025 600);
DISPLAY INVISIBLE (-5025 600);
FORCEPROP 1 LAST COMMENT_BODY TRUE
J 0
(-5225 625);
DISPLAY 0.872340 (-5225 625);
PAINT GREEN (-5225 625);
DISPLAY INVISIBLE (-5225 625);
FORCEPROP 2 LAST PATH I87
J 0
(-5300 800);
DISPLAY 0.680851 (-5300 800);
DISPLAY INVISIBLE (-5300 800);
FORCEADD Q_RES..1
(-2300 725);
FORCEPROP 1 LAST LOCATION R1525
J 0
(-2350 750);
DISPLAY 0.638298 (-2350 750);
FORCEPROP 0 LAST $SEC 1
J 0
(-2350 800);
DISPLAY 0.680851 (-2350 800);
PAINT MONO (-2350 800);
DISPLAY INVISIBLE (-2350 800);
FORCEPROP 0 LAST CDS_SEC 1
J 0
(-2350 800);
DISPLAY 0.680851 (-2350 800);
DISPLAY INVISIBLE (-2350 800);
FORCEPROP 1 LASTPIN (-2400 725) $PN 1
J 0
(-2388 737);
DISPLAY 0.787234 (-2388 737);
PAINT MONO (-2388 737);
FORCEPROP 1 LASTPIN (-2200 725) $PN 2
J 0
(-2238 737);
DISPLAY 0.787234 (-2238 737);
PAINT MONO (-2238 737);
FORCEPROP 1 LAST MATERIAL EMPTY
J 0
(-2500 725);
DISPLAY 0.510638 (-2500 725);
PAINT RED (-2500 725);
FORCEPROP 1 LAST VALUE 0
J 2
(-2150 725);
DISPLAY 0.510638 (-2150 725);
FORCEPROP 1 LAST TOLERANCE 5%
J 0
(-2125 725);
DISPLAY 0.510638 (-2125 725);
FORCEPROP 1 LAST PACK_TYPE 0402LF
J 0
(-2050 725);
DISPLAY 0.510638 (-2050 725);
DISPLAY INVISIBLE (-2050 725);
FORCEPROP 1 LAST WATTAGE 1/16W
J 2
(-2200 650);
DISPLAY 0.319149 (-2200 650);
DISPLAY INVISIBLE (-2200 650);
FORCEPROP 2 LAST CDS_LIB pure_quanta
J 0
(-2300 725);
DISPLAY INVISIBLE (-2300 725);
FORCEPROP 1 LAST PATH I88
J 0
(-2350 875);
DISPLAY 0.978723 (-2350 875);
PAINT WHITE (-2350 875);
DISPLAY INVISIBLE (-2350 875);
FORCEPROP 1 LAST PART_NUMBER CS00002JB13
J 0
(-2375 675);
DISPLAY 0.319149 (-2375 675);
DISPLAY INVISIBLE (-2375 675);
FORCEADD Q_RES..1
(-2875 575);
FORCEPROP 1 LAST LOCATION R1524
J 0
(-2925 625);
DISPLAY 0.978723 (-2925 625);
FORCEPROP 0 LAST $SEC 1
J 0
(-2925 675);
DISPLAY 0.680851 (-2925 675);
PAINT MONO (-2925 675);
DISPLAY INVISIBLE (-2925 675);
FORCEPROP 0 LAST CDS_SEC 1
J 0
(-2925 675);
DISPLAY 0.680851 (-2925 675);
DISPLAY INVISIBLE (-2925 675);
FORCEPROP 1 LASTPIN (-2975 575) $PN 1
J 0
(-2963 587);
DISPLAY 0.787234 (-2963 587);
PAINT MONO (-2963 587);
FORCEPROP 1 LASTPIN (-2775 575) $PN 2
J 0
(-2813 587);
DISPLAY 0.787234 (-2813 587);
PAINT MONO (-2813 587);
FORCEPROP 1 LAST TOLERANCE 5%
J 0
(-2700 575);
DISPLAY 0.510638 (-2700 575);
FORCEPROP 1 LAST VALUE 0
J 2
(-2725 575);
DISPLAY 0.510638 (-2725 575);
FORCEPROP 1 LAST WATTAGE 1/16W
J 2
(-2675 500);
DISPLAY 0.510638 (-2675 500);
FORCEPROP 1 LAST MATERIAL CHIP
J 0
(-2950 500);
DISPLAY 0.510638 (-2950 500);
PAINT RED (-2950 500);
FORCEPROP 1 LAST PACK_TYPE 0402LF
J 0
(-2625 575);
DISPLAY 0.510638 (-2625 575);
FORCEPROP 2 LAST CDS_LIB pure_quanta
J 0
(-2875 575);
DISPLAY INVISIBLE (-2875 575);
FORCEPROP 1 LAST PATH I89
J 0
(-2925 725);
DISPLAY 0.978723 (-2925 725);
PAINT WHITE (-2925 725);
DISPLAY INVISIBLE (-2925 725);
FORCEPROP 1 LAST PART_NUMBER CS00002JB13
J 0
(-2950 525);
DISPLAY 0.510638 (-2950 525);
DISPLAY INVISIBLE (-2950 525);
FORCEADD UNIVERSAL_GND..1
(-3150 1375);
FORCEPROP 3 LASTPIN (-3150 1425) SIG_NAME GND\g
J 0
(-3140 1435);
DISPLAY 0.659574 (-3140 1435);
PAINT MONO (-3140 1435);
DISPLAY INVISIBLE (-3140 1435);
FORCEPROP 2 LAST CDS_LIB pure_quanta_power
J 0
(-3150 1375);
DISPLAY INVISIBLE (-3150 1375);
FORCEPROP 1 LAST HDL_POWER GND
J 1
(-3125 1300);
DISPLAY 0.872340 (-3125 1300);
PAINT GREEN (-3125 1300);
DISPLAY INVISIBLE (-3125 1300);
FORCEPROP 1 LAST PATH I9
J 0
(-3075 1375);
DISPLAY 0.872340 (-3075 1375);
PAINT AQUA (-3075 1375);
DISPLAY INVISIBLE (-3075 1375);
FORCEADD DESIGN_NOTE..1
(-675 -925);
FORCEPROP 0 LAST L1 FM_OCP_V3_2_AUX_PWR_EN SET TO HIGH BY DEFAULT
J 0
(-875 -1050);
DISPLAY 0.808511 (-875 -1050);
PAINT SKYBLUE (-875 -1050);
FORCEPROP 2 LAST CDS_LIB pure_quanta_power
J 0
(-675 -925);
DISPLAY INVISIBLE (-675 -925);
FORCEPROP 0 LAST L2 UART_2 BMC TO MB (BMC HOST)
J 0
(-875 -1125);
DISPLAY 0.808511 (-875 -1125);
PAINT SKYBLUE (-875 -1125);
DISPLAY INVISIBLE (-875 -1125);
FORCEPROP 1 LAST COMMENT_BODY TRUE
J 0
(-650 -825);
DISPLAY 0.978723 (-650 -825);
DISPLAY INVISIBLE (-650 -825);
FORCEADD DNS..2
(-2325 3475);
PAINT RED (-2325 3475);
FORCEPROP 2 LAST CDS_LIB mstr_misc
J 0
(-2325 3475);
DISPLAY INVISIBLE (-2325 3475);
FORCEPROP 1 LAST COMMENT_BODY TRUE
R 1
J 0
(-2250 3250);
DISPLAY 0.872340 (-2250 3250);
PAINT GREEN (-2250 3250);
DISPLAY INVISIBLE (-2250 3250);
FORCEADD DNS..2
(625 -1325);
PAINT RED (625 -1325);
FORCEPROP 2 LAST CDS_LIB mstr_misc
J 0
(625 -1325);
DISPLAY INVISIBLE (625 -1325);
FORCEPROP 1 LAST COMMENT_BODY TRUE
R 1
J 0
(700 -1550);
DISPLAY 0.872340 (700 -1550);
PAINT GREEN (700 -1550);
DISPLAY INVISIBLE (700 -1550);
FORCEADD DNS..2
(675 225);
PAINT RED (675 225);
FORCEPROP 2 LAST CDS_LIB mstr_misc
J 0
(675 225);
DISPLAY INVISIBLE (675 225);
FORCEPROP 1 LAST COMMENT_BODY TRUE
R 1
J 0
(750 0);
DISPLAY 0.872340 (750 0);
PAINT GREEN (750 0);
DISPLAY INVISIBLE (750 0);
FORCEADD DNS..2
(2575 -50);
PAINT RED (2575 -50);
FORCEPROP 2 LAST CDS_LIB mstr_misc
J 0
(2575 -50);
DISPLAY INVISIBLE (2575 -50);
FORCEPROP 1 LAST COMMENT_BODY TRUE
R 1
J 0
(2650 -275);
DISPLAY 0.872340 (2650 -275);
PAINT GREEN (2650 -275);
DISPLAY INVISIBLE (2650 -275);
FORCEADD QUANTA_TITLE_BLOCK_C..1
(3650 -1975);
FORCEPROP 0 LAST CDS_CON_LAST_MODIFIED Thu Sep 14 16:13:10 2023
J 0
(1765 -1960);
DISPLAY INVISIBLE (1765 -1960);
FORCEPROP 1 LAST CUSTOM_TXT_CDS <CON_LAST_MODIFIED>
J 0
(1765 -1960);
DISPLAY 0.978723 (1765 -1960);
FORCEPROP 2 LAST CUSTOM_TXT_CDS <XR_PAGE_TITLE>
J 0
(-4240 3275);
DISPLAY 0.638298 (-4240 3275);
PAINT PINK (-4240 3275);
DISPLAY INVISIBLE (-4240 3275);
FORCEPROP 1 LAST CUSTOM_TXT_CDS <NAME_2>
J 0
(475 -1925);
FORCEPROP 1 LAST CUSTOM_TXT_CDS <NAME_1>
J 0
(475 -1800);
FORCEPROP 1 LAST CUSTOM_TXT_CDS <Q_NUMBER>
J 0
(2247 -1872);
DISPLAY 1.212766 (2247 -1872);
FORCEPROP 1 LAST CUSTOM_TXT_CDS <Q_PROJ>
J 0
(1268 -1873);
DISPLAY 1.212766 (1268 -1873);
FORCEPROP 1 LAST CUSTOM_TXT_CDS <Q_REV>
J 0
(3466 -1872);
DISPLAY 1.212766 (3466 -1872);
FORCEPROP 1 LAST CUSTOM_TXT_CDS <CON_PAGE_NUM> OF <CON_TOTAL_PAGES>
J 0
(3204 -1957);
DISPLAY 0.978723 (3204 -1957);
FORCEPROP 1 LAST Q_TITLE V3_2_OCP3.0 HSC(3/3)
J 0
(-5716 -1949);
DISPLAY 2.446809 (-5716 -1949);
PAINT GREEN (-5716 -1949);
FORCEPROP 2 LAST PAGE_BORDER TRUE
J 0
(-4240 3275);
DISPLAY 0.638298 (-4240 3275);
PAINT PINK (-4240 3275);
DISPLAY INVISIBLE (-4240 3275);
FORCEPROP 1 LAST CDS_LMAN_SYM_OUTLINE -9475,6775,100,-125
J 0
(3650 -1975);
DISPLAY 0.468085 (3650 -1975);
PAINT GREEN (3650 -1975);
DISPLAY INVISIBLE (3650 -1975);
FORCEPROP 2 LAST CDS_LIB pure_quanta
J 0
(3650 -1975);
DISPLAY INVISIBLE (3650 -1975);
FORCEPROP 2 LAST CDS_XR_PAGE_TITLE CR-142 : @T6G_MB_LIB.T6G(SCH_1):PAGE142
J 0
(-4240 3275);
DISPLAY 0.638298 (-4240 3275);
PAINT PINK (-4240 3275);
DISPLAY INVISIBLE (-4240 3275);
FORCEPROP 1 LAST Q_DEPT BU9
J 1
(-113 -1926);
DISPLAY 1.957447 (-113 -1926);
PAINT GREEN (-113 -1926);
DISPLAY INVISIBLE (-113 -1926);
FORCEPROP 1 LAST COMMENT_BODY TRUE
J 0
(3662 -1988);
DISPLAY 0.978723 (3662 -1988);
PAINT GREEN (3662 -1988);
DISPLAY INVISIBLE (3662 -1988);
FORCEADD DNS..2
(-3500 -1000);
PAINT RED (-3500 -1000);
FORCEPROP 2 LAST CDS_LIB mstr_misc
J 0
(-3500 -1000);
DISPLAY INVISIBLE (-3500 -1000);
FORCEPROP 1 LAST COMMENT_BODY TRUE
R 1
J 0
(-3425 -1225);
DISPLAY 0.872340 (-3425 -1225);
PAINT GREEN (-3425 -1225);
DISPLAY INVISIBLE (-3425 -1225);
FORCEADD DNS..2
(-2325 700);
PAINT RED (-2325 700);
FORCEPROP 2 LAST CDS_LIB mstr_misc
J 0
(-2325 700);
DISPLAY INVISIBLE (-2325 700);
FORCEPROP 1 LAST COMMENT_BODY TRUE
R 1
J 0
(-2250 475);
DISPLAY 0.872340 (-2250 475);
PAINT GREEN (-2250 475);
DISPLAY INVISIBLE (-2250 475);
WIRE 16 -1 (-1825 -125)(-1825 50);
WIRE 16 -1 (-250 -275)(-250 -325);
WIRE 16 -1 (-1075 2125)(-1075 2025);
WIRE 16 -1 (-4075 2875)(-4075 2575);
WIRE 16 -1 (-4075 3725)(-4075 3975);
WIRE 16 -1 (-1425 4200)(-1425 3950);
WIRE 16 -1 (-350 3575)(-350 3425);
WIRE 16 -1 (-50 -600)(25 -600);
WIRE 16 -1 (-50 -600)(-50 -725);
WIRE 16 -1 (-3300 1900)(-3300 1825);
WIRE 16 -1 (-50 625)(0 625);
WIRE 16 -1 (-50 625)(-50 400);
WIRE 16 -1 (850 900)(850 850);
WIRE 16 -1 (2500 75)(2500 175);
WIRE 16 -1 (-25 2675)(-25 2600);
WIRE 16 -1 (2275 2900)(2275 2800);
WIRE 16 -1 (-5150 -1500)(-5150 -1625);
WIRE 16 -1 (-3525 -1625)(-3525 -1725);
WIRE 16 -1 (-4225 -1050)(-4050 -1050);
WIRE 16 -1 (-4050 -1050)(-4050 -1100);
WIRE 16 -1 (-3375 -850)(-3375 -775);
WIRE 16 -1 (-4625 525)(-4575 525);
WIRE 16 -1 (-4625 525)(-4625 325);
WIRE 16 -1 (-3850 875)(-3850 800);
WIRE 16 -1 (-3850 1150)(-3950 1150);
WIRE 16 -1 (-3850 1225)(-3850 1150);
WIRE 16 -1 (-3850 1075)(-3850 1150);
WIRE 16 -1 (-3950 725)(-3950 1150);
WIRE 16 -1 (-3950 725)(-3975 725);
WIRE 16 -1 (700 825)(700 1175);
WIRE 16 -1 (600 825)(700 825);
WIRE 16 -1 (700 1175)(850 1175);
WIRE 16 -1 (850 1100)(850 1175);
WIRE 16 -1 (850 1175)(850 1225);
WIRE 16 -1 (-5150 -1150)(-4975 -1150);
WIRE 16 -1 (-5150 -925)(-5150 -1150);
WIRE 16 -1 (-5150 -1150)(-5150 -1300);
WIRE 16 -1 (25 -400)(-75 -400);
WIRE 16 -1 (-75 -400)(-75 -50);
WIRE 16 -1 (-225 -50)(-75 -50);
WIRE 16 -1 (-250 -50)(-225 -50);
WIRE 16 -1 (-225 -50)(-225 0);
WIRE 16 -1 (-250 -75)(-250 -50);
WIRE 16 -1 (-3275 2225)(-3175 2225);
WIRE 16 -1 (-3300 2225)(-3275 2225);
WIRE 16 -1 (-3275 2225)(-3275 2275);
WIRE 16 -1 (-3175 2225)(-3175 1675);
WIRE 16 -1 (-3175 1675)(-2750 1675);
WIRE 16 -1 (-3300 2100)(-3300 2225);
WIRE 16 -1 (-350 3900)(-350 3850);
WIRE 16 -1 (-350 3850)(-350 3775);
WIRE 16 -1 (-525 3850)(-350 3850);
WIRE 16 -1 (-525 3425)(-525 3850);
WIRE 16 -1 (-650 3425)(-525 3425);
WIRE 16 -1 (100 2450)(525 2450);
WIRE 16 -1 (100 3000)(100 2450);
WIRE 16 -1 (0 3000)(100 3000);
WIRE 16 -1 (-25 3000)(0 3000);
WIRE 16 -1 (0 3000)(0 3050);
WIRE 16 -1 (-25 2875)(-25 3000);
WIRE 16 -1 (125 2250)(525 2250);
WIRE 16 -1 (125 2200)(125 2250);
WIRE 16 -1 (-1525 3225)(-1250 3225);
WIRE 16 -1 (-1525 3000)(-1525 3225);
WIRE 16 -1 (-3150 1475)(-2750 1475);
WIRE 16 -1 (-3150 1425)(-3150 1475);
WIRE 16 -1 (-1575 725)(-1575 575);
WIRE 16 -1 (-1575 725)(-1300 725);
WIRE 16 -1 (-2200 725)(-1575 725);
FORCEPROP 2 LAST SIG_NAME OCP_V3_2_P3V3_R3_PWRGD
J 0
(-2035 735);
DISPLAY 0.553191 (-2035 735);
FORCEPROP 2 LASTPROP $XRERR UNIQUE?
J 0
(-2275 735);
DISPLAY 0.638298 (-2275 735);
PAINT MONO (-2275 735);
DISPLAY INVISIBLE (-2275 735);
WIRE 16 -1 (-2775 575)(-1575 575);
WIRE 16 -1 (-1575 575)(-1575 -450);
WIRE 16 -1 (-1575 -450)(-1375 -450);
WIRE 16 -1 (-2400 1575)(-1625 1575);
FORCEPROP 2 LAST SIG_NAME P12V_OCP_V3_2_PLD_R_PWRGD
J 0
(-2310 1585);
DISPLAY 0.553191 (-2310 1585);
PAINT SKYBLUE (-2310 1585);
FORCEPROP 2 LASTPROP $XRERR UNIQUE?
J 0
(-2550 1585);
DISPLAY 0.638298 (-2550 1585);
PAINT MONO (-2550 1585);
DISPLAY INVISIBLE (-2550 1585);
WIRE 16 -1 (-3150 725)(-2400 725);
FORCEPROP 2 LAST SIG_NAME OCP_V3_2_P3V3_PWRGD
J 0
(-3035 735);
DISPLAY 0.553191 (-3035 735);
PAINT SKYBLUE (-3035 735);
WIRE 16 -1 (-1100 725)(0 725);
FORCEPROP 0 LAST SIG_NAME HP_LVC3_OCP_V3_2_PWRGD
J 0
(-825 735);
DISPLAY 0.680851 (-825 735);
PAINT SKYBLUE (-825 735);
FORCEPROP 2 LASTPROP $XRERR UNIQUE?
J 0
(-1065 735);
DISPLAY 0.638298 (-1065 735);
PAINT MONO (-1065 735);
DISPLAY INVISIBLE (-1065 735);
WIRE 16 -1 (-4225 75)(-2800 75);
FORCEPROP 2 LAST SIG_NAME HP_LVC3_OCP_V3_2_P12V_PWRGD_R2
J 0
(-3860 85);
DISPLAY 0.680851 (-3860 85);
WIRE 16 -1 (-3975 575)(-2975 575);
FORCEPROP 2 LAST SIG_NAME HP_LVC3_OCP_V3_2_PWRGD_R2
J 0
(-3910 585);
DISPLAY 0.680851 (-3910 585);
FORCEPROP 2 LASTPROP $XRERR UNIQUE?
J 0
(-4150 585);
DISPLAY 0.638298 (-4150 585);
PAINT MONO (-4150 585);
DISPLAY INVISIBLE (-4150 585);
WIRE 16 -1 (1950 675)(2900 675);
FORCEPROP 2 LAST SIG_NAME RST_PERST_OCP_V3_2_BUF_N
J 0
(2125 685);
DISPLAY 0.680851 (2125 685);
PAINT SKYBLUE (2125 685);
WIRE 16 -1 (2275 2600)(2275 2350);
WIRE 16 -1 (3150 2350)(2275 2350);
FORCEPROP 2 LAST SIG_NAME OCP_V3_2_P3V3_PLD_R_PWRGD
J 0
(2290 2360);
DISPLAY 0.680851 (2290 2360);
PAINT SKYBLUE (2290 2360);
WIRE 16 -1 (1875 2350)(2275 2350);
WIRE 16 -1 (875 2350)(1675 2350);
FORCEPROP 2 LAST SIG_NAME OCP_V3_2_P3V3_PLD_PWRGD
J 0
(915 2360);
DISPLAY 0.680851 (915 2360);
PAINT SKYBLUE (915 2360);
FORCEPROP 2 LASTPROP $XRERR UNIQUE?
J 0
(675 2360);
DISPLAY 0.638298 (675 2360);
PAINT MONO (675 2360);
DISPLAY INVISIBLE (675 2360);
WIRE 16 -1 (550 3275)(1600 3275);
FORCEPROP 2 LAST SIG_NAME P12V_OCP_V3_2_BUF_EN_R
J 0
(890 3285);
DISPLAY 0.680851 (890 3285);
PAINT SKYBLUE (890 3285);
WIRE 16 -1 (-650 3275)(350 3275);
FORCEPROP 2 LAST SIG_NAME P12V_OCP_V3_2_BUF_EN
J 0
(-485 3310);
DISPLAY 0.851064 (-485 3310);
PAINT SKYBLUE (-485 3310);
FORCEPROP 2 LASTPROP $XRERR UNIQUE?
J 0
(-725 3310);
DISPLAY 0.638298 (-725 3310);
PAINT MONO (-725 3310);
DISPLAY INVISIBLE (-725 3310);
WIRE 16 -1 (-2225 3425)(-1425 3425);
FORCEPROP 2 LAST SIG_NAME P12V_OCP_V3_2_EN_R3
J 0
(-2060 3435);
DISPLAY 0.680851 (-2060 3435);
PAINT SKYBLUE (-2060 3435);
FORCEPROP 2 LASTPROP $XRERR UNIQUE?
J 0
(-2300 3435);
DISPLAY 0.638298 (-2300 3435);
PAINT MONO (-2300 3435);
DISPLAY INVISIBLE (-2300 3435);
WIRE 16 -1 (-1425 3750)(-1425 3425);
WIRE 16 -1 (-1250 3425)(-1425 3425);
WIRE 16 -1 (-2425 3425)(-3200 3425);
FORCEPROP 2 LAST SIG_NAME P12V_OCP_V3_2_EN_R
J 0
(-3135 3435);
DISPLAY 0.680851 (-3135 3435);
PAINT SKYBLUE (-3135 3435);
WIRE 16 -1 (1725 -500)(2500 -500);
FORCEPROP 2 LAST SIG_NAME OCP_V3_2_AUX_PWR_EN
J 0
(1900 -490);
DISPLAY 0.680851 (1900 -490);
PAINT SKYBLUE (1900 -490);
WIRE 16 -1 (2500 -125)(2500 -500);
WIRE 16 -1 (2500 -500)(2550 -500);
WIRE 16 -1 (1325 -500)(1325 200);
WIRE 16 -1 (1325 -500)(1525 -500);
WIRE 16 -1 (1325 -500)(1325 -1300);
WIRE 16 -1 (525 -500)(1325 -500);
FORCEPROP 0 LAST SIG_NAME OCP_V3_2_AUX_PWR_EN_R2
J 0
(590 -465);
DISPLAY 0.680851 (590 -465);
PAINT SKYBLUE (590 -465);
FORCEPROP 2 LASTPROP $XRERR UNIQUE?
J 0
(350 -465);
DISPLAY 0.638298 (350 -465);
PAINT MONO (350 -465);
DISPLAY INVISIBLE (350 -465);
WIRE 16 -1 (1325 200)(725 200);
WIRE 16 -1 (1325 -1300)(725 -1300);
WIRE 16 -1 (-4225 2975)(-5150 2975);
FORCEPROP 2 LAST SIG_NAME HP_LVC3_OCP_V3_2_PRSNT2_N
J 0
(-5135 2985);
DISPLAY 0.680851 (-5135 2985);
PAINT SKYBLUE (-5135 2985);
WIRE 16 -1 (-1400 2350)(-750 2350);
FORCEPROP 2 LAST SIG_NAME OCP_V3_2_P3V3_PWRGD
J 0
(-1385 2360);
DISPLAY 0.680851 (-1385 2360);
PAINT SKYBLUE (-1385 2360);
WIRE 16 -1 (-1175 -450)(-1000 -450);
FORCEPROP 0 LAST SIG_NAME HP_LVC3_OCP_V3_2_PWRGD_R1
J 0
(-985 -440);
DISPLAY 0.680851 (-985 -440);
PAINT SKYBLUE (-985 -440);
FORCEPROP 2 LASTPROP $XRERR UNIQUE?
J 0
(-1225 -440);
DISPLAY 0.638298 (-1225 -440);
PAINT MONO (-1225 -440);
DISPLAY INVISIBLE (-1225 -440);
WIRE 16 -1 (-1000 -450)(-1000 200);
WIRE 16 -1 (-1000 -450)(-75 -450);
WIRE 16 -1 (525 200)(-1000 200);
WIRE 16 -1 (-4225 -1250)(-3525 -1250);
FORCEPROP 2 LAST SIG_NAME OCP_V3_2_P3V3_R1_PWRGD
J 0
(-4110 -1240);
DISPLAY 0.680851 (-4110 -1240);
FORCEPROP 2 LASTPROP $XRERR UNIQUE?
J 0
(-4350 -1240);
DISPLAY 0.638298 (-4350 -1240);
PAINT MONO (-4350 -1240);
DISPLAY INVISIBLE (-4350 -1240);
WIRE 16 -1 (-3375 -1250)(-3525 -1250);
WIRE 16 -1 (-3525 -1425)(-3525 -1250);
WIRE 16 -1 (-3375 -1250)(-3150 -1250);
WIRE 16 -1 (-3375 -1050)(-3375 -1250);
WIRE 16 -1 (-75 -550)(-1000 -550);
WIRE 16 -1 (-1000 -550)(-1000 -1300);
WIRE 16 -1 (-1000 -550)(-1825 -550);
FORCEPROP 2 LAST SIG_NAME FM_OCP_V3_2_AUX_PWR_R_EN
J 0
(-1010 -540);
DISPLAY 0.680851 (-1010 -540);
PAINT SKYBLUE (-1010 -540);
WIRE 16 -1 (-1825 -325)(-1825 -550);
WIRE 16 -1 (-1825 -550)(-2125 -550);
WIRE 16 -1 (-1000 -1300)(525 -1300);
WIRE 16 -1 (0 825)(-1100 825);
FORCEPROP 2 LAST SIG_NAME RST_PERST_OCP_V3_2_R_N
J 0
(-825 835);
DISPLAY 0.680851 (-825 835);
PAINT SKYBLUE (-825 835);
FORCEPROP 2 LASTPROP $XRERR UNIQUE?
J 0
(-1065 835);
DISPLAY 0.638298 (-1065 835);
PAINT MONO (-1065 835);
DISPLAY INVISIBLE (-1065 835);
WIRE 16 -1 (600 675)(1750 675);
FORCEPROP 2 LAST SIG_NAME RST_PERST_OCP_V3_2_BUF_R_N
J 0
(765 700);
DISPLAY 0.680851 (765 700);
PAINT SKYBLUE (765 700);
FORCEPROP 2 LASTPROP $XRERR UNIQUE?
J 0
(525 700);
DISPLAY 0.638298 (525 700);
PAINT MONO (525 700);
DISPLAY INVISIBLE (525 700);
WIRE 16 -1 (-2750 1575)(-3900 1575);
FORCEPROP 2 LAST SIG_NAME HP_LVC3_OCP_V3_2_P12V_R_PWRGD
J 0
(-3585 1585);
DISPLAY 0.553191 (-3585 1585);
PAINT SKYBLUE (-3585 1585);
FORCEPROP 2 LASTPROP $XRERR UNIQUE?
J 0
(-3825 1585);
DISPLAY 0.638298 (-3825 1585);
PAINT MONO (-3825 1585);
DISPLAY INVISIBLE (-3825 1585);
WIRE 16 -1 (-5025 1575)(-4100 1575);
FORCEPROP 2 LAST SIG_NAME HP_LVC3_OCP_V3_2_P12V_PWRGD
J 0
(-4985 1585);
DISPLAY 0.680851 (-4985 1585);
PAINT SKYBLUE (-4985 1585);
WIRE 16 -1 (-2950 -1250)(-1750 -1250);
FORCEPROP 2 LAST SIG_NAME OCP_V3_2_P3V3_PWRGD
J 0
(-2585 -1240);
DISPLAY 0.680851 (-2585 -1240);
WIRE 16 -1 (-4425 75)(-5375 75);
FORCEPROP 2 LAST SIG_NAME HP_LVC3_OCP_V3_2_P12V_PWRGD
J 0
(-5335 85);
DISPLAY 0.680851 (-5335 85);
WIRE 16 -1 (-4575 625)(-5300 625);
FORCEPROP 2 LAST SIG_NAME HP_LVC3_OCP_V3_2_P12V_PWRGD_R2
J 0
(-5260 635);
DISPLAY 0.446809 (-5260 635);
WIRE 16 -1 (-4575 725)(-5300 725);
FORCEPROP 2 LAST SIG_NAME OCP_V3_2_P3V3_PWRGD
J 0
(-5260 735);
DISPLAY 0.680851 (-5260 735);
WIRE 16 -1 (-1075 1825)(-1075 1575);
WIRE 16 -1 (-400 1575)(-1075 1575);
FORCEPROP 2 LAST SIG_NAME P12V_OCP_V3_2_PLD_PWRGD
J 0
(-1035 1610);
DISPLAY 0.553191 (-1035 1610);
PAINT SKYBLUE (-1035 1610);
WIRE 16 -1 (-1425 1575)(-1075 1575);
WIRE 16 -1 (525 2350)(-550 2350);
FORCEPROP 2 LAST SIG_NAME OCP_V3_2_P3V3_R2_PWRGD
J 0
(-210 2360);
DISPLAY 0.680851 (-210 2360);
PAINT SKYBLUE (-210 2360);
FORCEPROP 2 LASTPROP $XRERR UNIQUE?
J 0
(-450 2360);
DISPLAY 0.638298 (-450 2360);
PAINT MONO (-450 2360);
DISPLAY INVISIBLE (-450 2360);
WIRE 16 -1 (-4075 3525)(-4075 3325);
WIRE 16 -1 (-1250 3325)(-4075 3325);
FORCEPROP 2 LAST SIG_NAME HP_LVC3_OCP_V3_2_PRSNT2
J 0
(-3810 3335);
DISPLAY 0.680851 (-3810 3335);
PAINT SKYBLUE (-3810 3335);
FORCEPROP 2 LASTPROP $XRERR UNIQUE?
J 0
(-4050 3335);
DISPLAY 0.638298 (-4050 3335);
PAINT MONO (-4050 3335);
DISPLAY INVISIBLE (-4050 3335);
WIRE 16 -1 (-4075 3175)(-4075 3325);
WIRE 16 -1 (-2100 825)(-1300 825);
FORCEPROP 2 LAST SIG_NAME RST_PERST_OCP_V3_2_N
J 0
(-2085 835);
DISPLAY 0.680851 (-2085 835);
PAINT SKYBLUE (-2085 835);
DOT 1 (-1575 575);
DOT 1 (-1575 725);
DOT 1 (-3850 1150);
DOT 1 (-5150 -1150);
DOT 1 (-3275 2225);
DOT 1 (-1825 -550);
DOT 1 (-1000 -550);
DOT 1 (-225 -50);
DOT 1 (-1075 1575);
DOT 1 (-4075 3325);
DOT 1 (-1425 3425);
DOT 1 (-350 3850);
DOT 1 (1325 -500);
DOT 1 (850 1175);
DOT 1 (2500 -500);
DOT 1 (0 3000);
DOT 1 (2275 2350);
DOT 1 (-1000 -450);
DOT 1 (-3525 -1250);
DOT 1 (-3375 -1250);
FORCENOTE
PUSH PULL OUTPUT
(-5050 -1475) 0;
DISPLAY LEFT (-5050 -1475);
DISPLAY 1.276596 (-5050 -1475);
FORCENOTE
P3V3_OCP_V3_2 PWRGD
(-2550 -1425) 0;
DISPLAY LEFT (-2550 -1425);
DISPLAY 1.021277 (-2550 -1425);
FORCENOTE
PUSH PULL
(-4450 375) 0;
DISPLAY LEFT (-4450 375);
DISPLAY 1.021277 (-4450 375);
FORCENOTE
OPEN DRAIN
(-2800 1325) 0;
DISPLAY LEFT (-2800 1325);
DISPLAY 1.021277 (-2800 1325);
FORCENOTE
PUSH PULL
(125 475) 0;
DISPLAY LEFT (125 475);
DISPLAY 1.021277 (125 475);
FORCENOTE
OCP CARD PRSNT
(-5175 2850) 0;
DISPLAY LEFT (-5175 2850);
DISPLAY 1.021277 (-5175 2850);
FORCENOTE
FROM CPLD
(-3475 3550) 0;
DISPLAY LEFT (-3475 3550);
DISPLAY 1.021277 (-3475 3550);
FORCENOTE
PUSH PULL
(-1150 3075) 0;
DISPLAY LEFT (-1150 3075);
DISPLAY 1.021277 (-1150 3075);
FORCENOTE
TO OCP_12V_HSC EN
(950 3175) 0;
DISPLAY LEFT (950 3175);
DISPLAY 1.021277 (950 3175);
FORCENOTE
OPEN DRAIN
(475 2100) 0;
DISPLAY LEFT (475 2100);
DISPLAY 1.021277 (475 2100);
QUIT
